FILE_TYPE = MACRO_DRAWING;
SET COLOR_WIRE YELLOW;
SET COLOR_PROP MONO;
SET COLOR_DOT WHITE;
SET COLOR_ARC YELLOW;
SET COLOR_BODY GREEN;
SET COLOR_NOTE MONO;
SET PROP_DISPLAY VALUE;
SET PAGE_NUMBER P106;
FORCEADD CAP..1
R 2
(-4100 2650);
FORCEPROP 1 LAST LOCATION C1R2
J 2
(-4150 2750);
DISPLAY 0.617021 (-4150 2750);
PAINT AQUA (-4150 2750);
FORCEPROP 1 LAST VALUE 0.22UF
J 2
(-4150 2700);
DISPLAY 0.617021 (-4150 2700);
PAINT SKYBLUE (-4150 2700);
FORCEPROP 1 LAST PACK_TYPE 0402
J 2
(-4150 2450);
DISPLAY 0.617021 (-4150 2450);
PAINT SKYBLUE (-4150 2450);
FORCEPROP 1 LAST VOLTAGE 16V
J 2
(-4150 2650);
DISPLAY 0.617021 (-4150 2650);
PAINT SKYBLUE (-4150 2650);
FORCEPROP 1 LAST MATERIAL X7R
J 2
(-4150 2550);
DISPLAY 0.617021 (-4150 2550);
PAINT SKYBLUE (-4150 2550);
FORCEPROP 1 LAST PART_NUMBER A36096-155
J 2
(-4150 2500);
DISPLAY 0.617021 (-4150 2500);
PAINT BLUE (-4150 2500);
FORCEPROP 1 LAST TOLERANCE 10%
J 2
(-4150 2600);
DISPLAY 0.617021 (-4150 2600);
PAINT SKYBLUE (-4150 2600);
FORCEPROP 2 LAST BOM_COST IO_SLOT
J 0
(-4350 2800);
PAINT MONO (-4350 2800);
DISPLAY INVISIBLE (-4350 2800);
FORCEPROP 2 LAST CDS_LIB mstr_discrete
J 0
(-4100 2650);
PAINT ORANGE (-4100 2650);
DISPLAY INVISIBLE (-4100 2650);
FORCEPROP 0 LAST CDS_SEC 1
J 0
(-4150 2800);
PAINT ORANGE (-4150 2800);
DISPLAY INVISIBLE (-4150 2800);
FORCEPROP 2 LAST $SEC 1
J 0
(-4150 2850);
DISPLAY 0.680851 (-4150 2850);
PAINT MONO (-4150 2850);
DISPLAY INVISIBLE (-4150 2850);
FORCEPROP 2 LAST CDS_LOCATION C1R2
J 2
(-4150 2750);
DISPLAY 0.617021 (-4150 2750);
PAINT AQUA (-4150 2750);
DISPLAY INVISIBLE (-4150 2750);
FORCEPROP 1 LAST PATH I10
J 2
(-4150 2800);
DISPLAY 0.978723 (-4150 2800);
PAINT WHITE (-4150 2800);
DISPLAY INVISIBLE (-4150 2800);
FORCEPROP 2 LAST ROOM PCIE_STEERING
J 2
(-4100 2650);
PAINT MONO (-4100 2650);
DISPLAY INVISIBLE (-4100 2650);
FORCEPROP 1 LASTPIN (-4100 2550) $PN 2
J 2
(-4110 2530);
DISPLAY 0.787234 (-4110 2530);
PAINT ORANGE (-4110 2530);
DISPLAY INVISIBLE (-4110 2530);
FORCEPROP 1 LASTPIN (-4100 2750) $PN 1
J 2
(-4110 2730);
DISPLAY 0.787234 (-4110 2730);
PAINT ORANGE (-4110 2730);
DISPLAY INVISIBLE (-4110 2730);
FORCEADD CAP..1
R 2
(-6500 2650);
FORCEPROP 1 LAST LOCATION C1M12
J 2
(-6550 2750);
DISPLAY 0.617021 (-6550 2750);
PAINT AQUA (-6550 2750);
FORCEPROP 1 LAST PART_NUMBER A36096-155
J 2
(-6550 2500);
DISPLAY 0.617021 (-6550 2500);
PAINT BLUE (-6550 2500);
FORCEPROP 1 LAST VALUE 0.22UF
J 2
(-6550 2700);
DISPLAY 0.617021 (-6550 2700);
PAINT SKYBLUE (-6550 2700);
FORCEPROP 1 LAST TOLERANCE 10%
J 2
(-6550 2600);
DISPLAY 0.617021 (-6550 2600);
PAINT SKYBLUE (-6550 2600);
FORCEPROP 1 LAST PACK_TYPE 0402
J 2
(-6550 2450);
DISPLAY 0.617021 (-6550 2450);
PAINT SKYBLUE (-6550 2450);
FORCEPROP 1 LAST VOLTAGE 16V
J 2
(-6550 2650);
DISPLAY 0.617021 (-6550 2650);
PAINT SKYBLUE (-6550 2650);
FORCEPROP 1 LAST MATERIAL X7R
J 2
(-6550 2550);
DISPLAY 0.617021 (-6550 2550);
PAINT SKYBLUE (-6550 2550);
FORCEPROP 2 LAST CDS_LIB mstr_discrete
J 0
(-6500 2650);
PAINT ORANGE (-6500 2650);
DISPLAY INVISIBLE (-6500 2650);
FORCEPROP 2 LAST BOM_COST IO_SLOT
J 0
(-6750 2800);
PAINT MONO (-6750 2800);
DISPLAY INVISIBLE (-6750 2800);
FORCEPROP 0 LAST CDS_SEC 1
J 0
(-6550 2800);
PAINT ORANGE (-6550 2800);
DISPLAY INVISIBLE (-6550 2800);
FORCEPROP 2 LAST $SEC 1
J 0
(-6550 2850);
DISPLAY 0.680851 (-6550 2850);
PAINT MONO (-6550 2850);
DISPLAY INVISIBLE (-6550 2850);
FORCEPROP 2 LAST CDS_LOCATION C1M12
J 2
(-6550 2750);
DISPLAY 0.617021 (-6550 2750);
PAINT AQUA (-6550 2750);
DISPLAY INVISIBLE (-6550 2750);
FORCEPROP 1 LAST PATH I100
J 2
(-6550 2800);
DISPLAY 0.978723 (-6550 2800);
PAINT WHITE (-6550 2800);
DISPLAY INVISIBLE (-6550 2800);
FORCEPROP 2 LAST ROOM PCIE_STEERING
J 2
(-6500 2650);
PAINT MONO (-6500 2650);
DISPLAY INVISIBLE (-6500 2650);
FORCEPROP 1 LASTPIN (-6500 2550) $PN 2
J 2
(-6510 2530);
DISPLAY 0.787234 (-6510 2530);
PAINT ORANGE (-6510 2530);
DISPLAY INVISIBLE (-6510 2530);
FORCEPROP 1 LASTPIN (-6500 2750) $PN 1
J 2
(-6510 2730);
DISPLAY 0.787234 (-6510 2730);
PAINT ORANGE (-6510 2730);
DISPLAY INVISIBLE (-6510 2730);
FORCEADD TAP..7
(-6500 2100);
FORCEPROP 3 LASTPIN (-6500 2150) SIG_NAME P3E_OCP_CPU0_PE3_C_TXP<12>
J 0
(-6490 2160);
DISPLAY 0.659574 (-6490 2160);
PAINT MONO (-6490 2160);
DISPLAY INVISIBLE (-6490 2160);
FORCEPROP 1 LASTPIN (-6500 2150) BN 12
R 1
J 0
(-6507 2098);
DISPLAY 0.617021 (-6507 2098);
PAINT GREEN (-6507 2098);
FORCEPROP 2 LAST CDS_LIB mstr_standard
J 0
(-6500 2100);
PAINT ORANGE (-6500 2100);
DISPLAY INVISIBLE (-6500 2100);
FORCEPROP 1 LAST BODY_TYPE PLUMBING
J 0
(-6450 2100);
DISPLAY 2.276596 (-6450 2100);
PAINT GREEN (-6450 2100);
DISPLAY INVISIBLE (-6450 2100);
FORCEPROP 1 LAST HDL_TAP TRUE
J 0
(-6180 1970);
DISPLAY 2.276596 (-6180 1970);
PAINT GREEN (-6180 1970);
DISPLAY INVISIBLE (-6180 1970);
FORCEPROP 1 LAST PATH I101
J 0
(-6502 2100);
DISPLAY 0.872340 (-6502 2100);
PAINT GREEN (-6502 2100);
DISPLAY INVISIBLE (-6502 2100);
FORCEADD CAP..1
R 2
(-6700 2350);
FORCEPROP 1 LAST LOCATION C1M10
J 2
(-6750 2450);
DISPLAY 0.617021 (-6750 2450);
PAINT AQUA (-6750 2450);
FORCEPROP 1 LAST PART_NUMBER A36096-155
J 2
(-6750 2200);
DISPLAY 0.617021 (-6750 2200);
PAINT BLUE (-6750 2200);
FORCEPROP 1 LAST VALUE 0.22UF
J 2
(-6750 2400);
DISPLAY 0.617021 (-6750 2400);
PAINT SKYBLUE (-6750 2400);
FORCEPROP 1 LAST TOLERANCE 10%
J 2
(-6750 2300);
DISPLAY 0.617021 (-6750 2300);
PAINT SKYBLUE (-6750 2300);
FORCEPROP 1 LAST PACK_TYPE 0402
J 2
(-6750 2150);
DISPLAY 0.617021 (-6750 2150);
PAINT SKYBLUE (-6750 2150);
FORCEPROP 1 LAST VOLTAGE 16V
J 2
(-6750 2350);
DISPLAY 0.617021 (-6750 2350);
PAINT SKYBLUE (-6750 2350);
FORCEPROP 1 LAST MATERIAL X7R
J 2
(-6750 2250);
DISPLAY 0.617021 (-6750 2250);
PAINT SKYBLUE (-6750 2250);
FORCEPROP 2 LAST CDS_LIB mstr_discrete
J 0
(-6700 2350);
PAINT ORANGE (-6700 2350);
DISPLAY INVISIBLE (-6700 2350);
FORCEPROP 2 LAST BOM_COST IO_SLOT
J 0
(-6950 2500);
PAINT MONO (-6950 2500);
DISPLAY INVISIBLE (-6950 2500);
FORCEPROP 0 LAST CDS_SEC 1
J 0
(-6750 2500);
PAINT ORANGE (-6750 2500);
DISPLAY INVISIBLE (-6750 2500);
FORCEPROP 2 LAST $SEC 1
J 0
(-6750 2550);
DISPLAY 0.680851 (-6750 2550);
PAINT MONO (-6750 2550);
DISPLAY INVISIBLE (-6750 2550);
FORCEPROP 2 LAST CDS_LOCATION C1M10
J 2
(-6750 2450);
DISPLAY 0.617021 (-6750 2450);
PAINT AQUA (-6750 2450);
DISPLAY INVISIBLE (-6750 2450);
FORCEPROP 1 LAST PATH I102
J 2
(-6750 2500);
DISPLAY 0.978723 (-6750 2500);
PAINT WHITE (-6750 2500);
DISPLAY INVISIBLE (-6750 2500);
FORCEPROP 2 LAST ROOM PCIE_STEERING
J 2
(-6700 2350);
PAINT MONO (-6700 2350);
DISPLAY INVISIBLE (-6700 2350);
FORCEPROP 1 LASTPIN (-6700 2250) $PN 2
J 2
(-6710 2230);
DISPLAY 0.787234 (-6710 2230);
PAINT ORANGE (-6710 2230);
DISPLAY INVISIBLE (-6710 2230);
FORCEPROP 1 LASTPIN (-6700 2450) $PN 1
J 2
(-6710 2430);
DISPLAY 0.787234 (-6710 2430);
PAINT ORANGE (-6710 2430);
DISPLAY INVISIBLE (-6710 2430);
FORCEADD TAP..7
(-6700 2100);
FORCEPROP 3 LASTPIN (-6700 2150) SIG_NAME P3E_OCP_CPU0_PE3_C_TXP<13>
J 0
(-6690 2160);
DISPLAY 0.659574 (-6690 2160);
PAINT MONO (-6690 2160);
DISPLAY INVISIBLE (-6690 2160);
FORCEPROP 1 LASTPIN (-6700 2150) BN 13
R 1
J 0
(-6707 2098);
DISPLAY 0.617021 (-6707 2098);
PAINT GREEN (-6707 2098);
FORCEPROP 2 LAST CDS_LIB mstr_standard
J 0
(-6700 2100);
PAINT ORANGE (-6700 2100);
DISPLAY INVISIBLE (-6700 2100);
FORCEPROP 1 LAST BODY_TYPE PLUMBING
J 0
(-6650 2100);
DISPLAY 2.276596 (-6650 2100);
PAINT GREEN (-6650 2100);
DISPLAY INVISIBLE (-6650 2100);
FORCEPROP 1 LAST HDL_TAP TRUE
J 0
(-6380 1970);
DISPLAY 2.276596 (-6380 1970);
PAINT GREEN (-6380 1970);
DISPLAY INVISIBLE (-6380 1970);
FORCEPROP 1 LAST PATH I103
J 0
(-6702 2100);
DISPLAY 0.872340 (-6702 2100);
PAINT GREEN (-6702 2100);
DISPLAY INVISIBLE (-6702 2100);
FORCEADD TAP..7
(-6900 2100);
FORCEPROP 3 LASTPIN (-6900 2150) SIG_NAME P3E_OCP_CPU0_PE3_C_TXP<14>
J 0
(-6890 2160);
DISPLAY 0.659574 (-6890 2160);
PAINT MONO (-6890 2160);
DISPLAY INVISIBLE (-6890 2160);
FORCEPROP 1 LASTPIN (-6900 2150) BN 14
R 1
J 0
(-6907 2098);
DISPLAY 0.617021 (-6907 2098);
PAINT GREEN (-6907 2098);
FORCEPROP 2 LAST CDS_LIB mstr_standard
J 0
(-6900 2100);
PAINT ORANGE (-6900 2100);
DISPLAY INVISIBLE (-6900 2100);
FORCEPROP 1 LAST BODY_TYPE PLUMBING
J 0
(-6850 2100);
DISPLAY 2.276596 (-6850 2100);
PAINT GREEN (-6850 2100);
DISPLAY INVISIBLE (-6850 2100);
FORCEPROP 1 LAST HDL_TAP TRUE
J 0
(-6580 1970);
DISPLAY 2.276596 (-6580 1970);
PAINT GREEN (-6580 1970);
DISPLAY INVISIBLE (-6580 1970);
FORCEPROP 1 LAST PATH I104
J 0
(-6902 2100);
DISPLAY 0.872340 (-6902 2100);
PAINT GREEN (-6902 2100);
DISPLAY INVISIBLE (-6902 2100);
FORCEADD CAP..1
R 2
(-6900 2650);
FORCEPROP 1 LAST LOCATION C1M8
J 2
(-6950 2750);
DISPLAY 0.617021 (-6950 2750);
PAINT AQUA (-6950 2750);
FORCEPROP 1 LAST PART_NUMBER A36096-155
J 2
(-6950 2500);
DISPLAY 0.617021 (-6950 2500);
PAINT BLUE (-6950 2500);
FORCEPROP 1 LAST VALUE 0.22UF
J 2
(-6950 2700);
DISPLAY 0.617021 (-6950 2700);
PAINT SKYBLUE (-6950 2700);
FORCEPROP 1 LAST TOLERANCE 10%
J 2
(-6950 2600);
DISPLAY 0.617021 (-6950 2600);
PAINT SKYBLUE (-6950 2600);
FORCEPROP 1 LAST PACK_TYPE 0402
J 2
(-6950 2450);
DISPLAY 0.617021 (-6950 2450);
PAINT SKYBLUE (-6950 2450);
FORCEPROP 1 LAST VOLTAGE 16V
J 2
(-6950 2650);
DISPLAY 0.617021 (-6950 2650);
PAINT SKYBLUE (-6950 2650);
FORCEPROP 1 LAST MATERIAL X7R
J 2
(-6950 2550);
DISPLAY 0.617021 (-6950 2550);
PAINT SKYBLUE (-6950 2550);
FORCEPROP 2 LAST CDS_LIB mstr_discrete
J 0
(-6900 2650);
PAINT ORANGE (-6900 2650);
DISPLAY INVISIBLE (-6900 2650);
FORCEPROP 0 LAST CDS_SEC 1
J 0
(-6950 2800);
PAINT ORANGE (-6950 2800);
DISPLAY INVISIBLE (-6950 2800);
FORCEPROP 2 LAST $SEC 1
J 0
(-6950 2850);
DISPLAY 0.680851 (-6950 2850);
PAINT MONO (-6950 2850);
DISPLAY INVISIBLE (-6950 2850);
FORCEPROP 2 LAST CDS_LOCATION C1M8
J 2
(-6950 2750);
DISPLAY 0.617021 (-6950 2750);
PAINT AQUA (-6950 2750);
DISPLAY INVISIBLE (-6950 2750);
FORCEPROP 1 LAST PATH I105
J 2
(-6950 2800);
DISPLAY 0.978723 (-6950 2800);
PAINT WHITE (-6950 2800);
DISPLAY INVISIBLE (-6950 2800);
FORCEPROP 2 LAST ROOM PCIE_STEERING
J 2
(-6900 2650);
PAINT MONO (-6900 2650);
DISPLAY INVISIBLE (-6900 2650);
FORCEPROP 1 LASTPIN (-6900 2550) $PN 2
J 2
(-6910 2530);
DISPLAY 0.787234 (-6910 2530);
PAINT ORANGE (-6910 2530);
DISPLAY INVISIBLE (-6910 2530);
FORCEPROP 1 LASTPIN (-6900 2750) $PN 1
J 2
(-6910 2730);
DISPLAY 0.787234 (-6910 2730);
PAINT ORANGE (-6910 2730);
DISPLAY INVISIBLE (-6910 2730);
FORCEADD TAP..3
(-7100 2900);
FORCEPROP 3 LASTPIN (-7100 2850) SIG_NAME P3E_CPU0_PE3_OCP_TXP<15>
J 0
(-7090 2860);
DISPLAY 0.659574 (-7090 2860);
PAINT MONO (-7090 2860);
DISPLAY INVISIBLE (-7090 2860);
FORCEPROP 1 LASTPIN (-7100 2850) BN 15
R 1
J 0
(-7107 2838);
DISPLAY 0.617021 (-7107 2838);
PAINT GREEN (-7107 2838);
FORCEPROP 2 LAST CDS_LIB mstr_standard
J 0
(-7100 2900);
PAINT ORANGE (-7100 2900);
DISPLAY INVISIBLE (-7100 2900);
FORCEPROP 1 LAST BODY_TYPE PLUMBING
J 0
(-7050 2850);
DISPLAY 2.276596 (-7050 2850);
PAINT GREEN (-7050 2850);
DISPLAY INVISIBLE (-7050 2850);
FORCEPROP 1 LAST HDL_TAP TRUE
J 0
(-6780 2770);
DISPLAY 2.276596 (-6780 2770);
PAINT GREEN (-6780 2770);
DISPLAY INVISIBLE (-6780 2770);
FORCEPROP 1 LAST PATH I106
J 0
(-7102 2900);
DISPLAY 0.872340 (-7102 2900);
PAINT GREEN (-7102 2900);
DISPLAY INVISIBLE (-7102 2900);
FORCEADD OFFPAGE..1
(-7275 2950);
FORCEPROP 2 LAST $XR0 32 
J 0
(-7496 2950);
DISPLAY 0.638298 (-7496 2950);
PAINT MONO (-7496 2950);
FORCEPROP 2 LAST CDS_LIB mstr_standard
J 0
(-7275 2950);
PAINT ORANGE (-7275 2950);
DISPLAY INVISIBLE (-7275 2950);
FORCEPROP 1 LAST OFFPAGE TRUE
J 0
(-6955 2820);
PAINT GREEN (-6955 2820);
DISPLAY INVISIBLE (-6955 2820);
FORCEPROP 1 LAST COMMENT_BODY TRUE
J 0
(-7155 2850);
DISPLAY 2.276596 (-7155 2850);
PAINT GREEN (-7155 2850);
DISPLAY INVISIBLE (-7155 2850);
FORCEPROP 2 LAST PATH I107
J 0
(-7525 3000);
DISPLAY 1.021277 (-7525 3000);
PAINT ORANGE (-7525 3000);
DISPLAY INVISIBLE (-7525 3000);
FORCEADD TAP..7
(-7100 2100);
FORCEPROP 3 LASTPIN (-7100 2150) SIG_NAME P3E_OCP_CPU0_PE3_C_TXP<15>
J 0
(-7090 2160);
DISPLAY 0.659574 (-7090 2160);
PAINT MONO (-7090 2160);
DISPLAY INVISIBLE (-7090 2160);
FORCEPROP 1 LASTPIN (-7100 2150) BN 15
R 1
J 0
(-7107 2098);
DISPLAY 0.617021 (-7107 2098);
PAINT GREEN (-7107 2098);
FORCEPROP 2 LAST CDS_LIB mstr_standard
J 0
(-7100 2100);
PAINT ORANGE (-7100 2100);
DISPLAY INVISIBLE (-7100 2100);
FORCEPROP 1 LAST BODY_TYPE PLUMBING
J 0
(-7050 2100);
DISPLAY 2.276596 (-7050 2100);
PAINT GREEN (-7050 2100);
DISPLAY INVISIBLE (-7050 2100);
FORCEPROP 1 LAST HDL_TAP TRUE
J 0
(-6780 1970);
DISPLAY 2.276596 (-6780 1970);
PAINT GREEN (-6780 1970);
DISPLAY INVISIBLE (-6780 1970);
FORCEPROP 1 LAST PATH I108
J 0
(-7102 2100);
DISPLAY 0.872340 (-7102 2100);
PAINT GREEN (-7102 2100);
DISPLAY INVISIBLE (-7102 2100);
FORCEADD CAP..1
R 2
(-7100 2350);
FORCEPROP 1 LAST LOCATION C1M6
J 2
(-7150 2450);
DISPLAY 0.617021 (-7150 2450);
PAINT AQUA (-7150 2450);
FORCEPROP 1 LAST PART_NUMBER A36096-155
J 2
(-7150 2200);
DISPLAY 0.617021 (-7150 2200);
PAINT BLUE (-7150 2200);
FORCEPROP 1 LAST VALUE 0.22UF
J 2
(-7150 2400);
DISPLAY 0.617021 (-7150 2400);
PAINT SKYBLUE (-7150 2400);
FORCEPROP 1 LAST TOLERANCE 10%
J 2
(-7150 2300);
DISPLAY 0.617021 (-7150 2300);
PAINT SKYBLUE (-7150 2300);
FORCEPROP 1 LAST PACK_TYPE 0402
J 2
(-7150 2150);
DISPLAY 0.617021 (-7150 2150);
PAINT SKYBLUE (-7150 2150);
FORCEPROP 1 LAST VOLTAGE 16V
J 2
(-7150 2350);
DISPLAY 0.617021 (-7150 2350);
PAINT SKYBLUE (-7150 2350);
FORCEPROP 1 LAST MATERIAL X7R
J 2
(-7150 2250);
DISPLAY 0.617021 (-7150 2250);
PAINT SKYBLUE (-7150 2250);
FORCEPROP 2 LAST CDS_LIB mstr_discrete
J 0
(-7100 2350);
PAINT ORANGE (-7100 2350);
DISPLAY INVISIBLE (-7100 2350);
FORCEPROP 0 LAST CDS_SEC 1
J 0
(-7150 2500);
PAINT ORANGE (-7150 2500);
DISPLAY INVISIBLE (-7150 2500);
FORCEPROP 2 LAST $SEC 1
J 0
(-7150 2550);
DISPLAY 0.680851 (-7150 2550);
PAINT MONO (-7150 2550);
DISPLAY INVISIBLE (-7150 2550);
FORCEPROP 2 LAST CDS_LOCATION C1M6
J 2
(-7150 2450);
DISPLAY 0.617021 (-7150 2450);
PAINT AQUA (-7150 2450);
DISPLAY INVISIBLE (-7150 2450);
FORCEPROP 1 LAST PATH I109
J 2
(-7150 2500);
DISPLAY 0.978723 (-7150 2500);
PAINT WHITE (-7150 2500);
DISPLAY INVISIBLE (-7150 2500);
FORCEPROP 2 LAST ROOM PCIE_STEERING
J 2
(-7100 2350);
PAINT MONO (-7100 2350);
DISPLAY INVISIBLE (-7100 2350);
FORCEPROP 1 LASTPIN (-7100 2250) $PN 2
J 2
(-7110 2230);
DISPLAY 0.787234 (-7110 2230);
PAINT ORANGE (-7110 2230);
DISPLAY INVISIBLE (-7110 2230);
FORCEPROP 1 LASTPIN (-7100 2450) $PN 1
J 2
(-7110 2430);
DISPLAY 0.787234 (-7110 2430);
PAINT ORANGE (-7110 2430);
DISPLAY INVISIBLE (-7110 2430);
FORCEADD TAP..3
(-4300 2900);
FORCEPROP 3 LASTPIN (-4300 2850) SIG_NAME P3E_CPU0_PE3_OCP_TXP<1>
J 0
(-4290 2860);
DISPLAY 0.659574 (-4290 2860);
PAINT MONO (-4290 2860);
DISPLAY INVISIBLE (-4290 2860);
FORCEPROP 1 LASTPIN (-4300 2850) BN 1
R 1
J 0
(-4307 2838);
DISPLAY 0.617021 (-4307 2838);
PAINT GREEN (-4307 2838);
FORCEPROP 2 LAST CDS_LIB mstr_standard
J 0
(-4300 2900);
PAINT ORANGE (-4300 2900);
DISPLAY INVISIBLE (-4300 2900);
FORCEPROP 1 LAST BODY_TYPE PLUMBING
J 0
(-4250 2850);
DISPLAY 2.276596 (-4250 2850);
PAINT GREEN (-4250 2850);
DISPLAY INVISIBLE (-4250 2850);
FORCEPROP 1 LAST HDL_TAP TRUE
J 0
(-3980 2770);
DISPLAY 2.276596 (-3980 2770);
PAINT GREEN (-3980 2770);
DISPLAY INVISIBLE (-3980 2770);
FORCEPROP 1 LAST PATH I11
J 0
(-4302 2900);
DISPLAY 0.872340 (-4302 2900);
PAINT GREEN (-4302 2900);
DISPLAY INVISIBLE (-4302 2900);
FORCEADD TAP..3
(-6450 1900);
FORCEPROP 3 LASTPIN (-6450 1850) SIG_NAME P3E_CPU0_PE3_OCP_TXN<12>
J 0
(-6440 1860);
DISPLAY 0.659574 (-6440 1860);
PAINT MONO (-6440 1860);
DISPLAY INVISIBLE (-6440 1860);
FORCEPROP 1 LASTPIN (-6450 1850) BN 12
R 1
J 0
(-6457 1838);
DISPLAY 0.617021 (-6457 1838);
PAINT GREEN (-6457 1838);
FORCEPROP 2 LAST CDS_LIB mstr_standard
J 0
(-6450 1900);
PAINT ORANGE (-6450 1900);
DISPLAY INVISIBLE (-6450 1900);
FORCEPROP 1 LAST BODY_TYPE PLUMBING
J 0
(-6400 1850);
DISPLAY 2.276596 (-6400 1850);
PAINT GREEN (-6400 1850);
DISPLAY INVISIBLE (-6400 1850);
FORCEPROP 1 LAST HDL_TAP TRUE
J 0
(-6130 1770);
DISPLAY 2.276596 (-6130 1770);
PAINT GREEN (-6130 1770);
DISPLAY INVISIBLE (-6130 1770);
FORCEPROP 1 LAST PATH I110
J 0
(-6452 1900);
DISPLAY 0.872340 (-6452 1900);
PAINT GREEN (-6452 1900);
DISPLAY INVISIBLE (-6452 1900);
FORCEADD CAP..1
R 2
(-6450 1650);
FORCEPROP 1 LAST LOCATION C1M13
J 2
(-6500 1750);
DISPLAY 0.617021 (-6500 1750);
PAINT AQUA (-6500 1750);
FORCEPROP 1 LAST PART_NUMBER A36096-155
J 2
(-6500 1500);
DISPLAY 0.617021 (-6500 1500);
PAINT BLUE (-6500 1500);
FORCEPROP 1 LAST VALUE 0.22UF
J 2
(-6500 1700);
DISPLAY 0.617021 (-6500 1700);
PAINT SKYBLUE (-6500 1700);
FORCEPROP 1 LAST TOLERANCE 10%
J 2
(-6500 1600);
DISPLAY 0.617021 (-6500 1600);
PAINT SKYBLUE (-6500 1600);
FORCEPROP 1 LAST PACK_TYPE 0402
J 2
(-6500 1450);
DISPLAY 0.617021 (-6500 1450);
PAINT SKYBLUE (-6500 1450);
FORCEPROP 1 LAST VOLTAGE 16V
J 2
(-6500 1650);
DISPLAY 0.617021 (-6500 1650);
PAINT SKYBLUE (-6500 1650);
FORCEPROP 1 LAST MATERIAL X7R
J 2
(-6500 1550);
DISPLAY 0.617021 (-6500 1550);
PAINT SKYBLUE (-6500 1550);
FORCEPROP 2 LAST CDS_LIB mstr_discrete
J 0
(-6450 1650);
PAINT ORANGE (-6450 1650);
DISPLAY INVISIBLE (-6450 1650);
FORCEPROP 2 LAST BOM_COST IO_SLOT
J 0
(-6700 1800);
PAINT MONO (-6700 1800);
DISPLAY INVISIBLE (-6700 1800);
FORCEPROP 0 LAST CDS_SEC 1
J 0
(-6500 1800);
PAINT ORANGE (-6500 1800);
DISPLAY INVISIBLE (-6500 1800);
FORCEPROP 2 LAST $SEC 1
J 0
(-6500 1850);
DISPLAY 0.680851 (-6500 1850);
PAINT MONO (-6500 1850);
DISPLAY INVISIBLE (-6500 1850);
FORCEPROP 2 LAST CDS_LOCATION C1M13
J 2
(-6500 1750);
DISPLAY 0.617021 (-6500 1750);
PAINT AQUA (-6500 1750);
DISPLAY INVISIBLE (-6500 1750);
FORCEPROP 1 LAST PATH I111
J 2
(-6500 1800);
DISPLAY 0.978723 (-6500 1800);
PAINT WHITE (-6500 1800);
DISPLAY INVISIBLE (-6500 1800);
FORCEPROP 2 LAST ROOM PCIE_STEERING
J 2
(-6450 1650);
PAINT MONO (-6450 1650);
DISPLAY INVISIBLE (-6450 1650);
FORCEPROP 1 LASTPIN (-6450 1550) $PN 2
J 2
(-6460 1530);
DISPLAY 0.787234 (-6460 1530);
PAINT ORANGE (-6460 1530);
DISPLAY INVISIBLE (-6460 1530);
FORCEPROP 1 LASTPIN (-6450 1750) $PN 1
J 2
(-6460 1730);
DISPLAY 0.787234 (-6460 1730);
PAINT ORANGE (-6460 1730);
DISPLAY INVISIBLE (-6460 1730);
FORCEADD TAP..3
(-6650 1900);
FORCEPROP 3 LASTPIN (-6650 1850) SIG_NAME P3E_CPU0_PE3_OCP_TXN<13>
J 0
(-6640 1860);
DISPLAY 0.659574 (-6640 1860);
PAINT MONO (-6640 1860);
DISPLAY INVISIBLE (-6640 1860);
FORCEPROP 1 LASTPIN (-6650 1850) BN 13
R 1
J 0
(-6657 1838);
DISPLAY 0.617021 (-6657 1838);
PAINT GREEN (-6657 1838);
FORCEPROP 2 LAST CDS_LIB mstr_standard
J 0
(-6650 1900);
PAINT ORANGE (-6650 1900);
DISPLAY INVISIBLE (-6650 1900);
FORCEPROP 1 LAST BODY_TYPE PLUMBING
J 0
(-6600 1850);
DISPLAY 2.276596 (-6600 1850);
PAINT GREEN (-6600 1850);
DISPLAY INVISIBLE (-6600 1850);
FORCEPROP 1 LAST HDL_TAP TRUE
J 0
(-6330 1770);
DISPLAY 2.276596 (-6330 1770);
PAINT GREEN (-6330 1770);
DISPLAY INVISIBLE (-6330 1770);
FORCEPROP 1 LAST PATH I112
J 0
(-6652 1900);
DISPLAY 0.872340 (-6652 1900);
PAINT GREEN (-6652 1900);
DISPLAY INVISIBLE (-6652 1900);
FORCEADD TAP..3
(-6850 1900);
FORCEPROP 3 LASTPIN (-6850 1850) SIG_NAME P3E_CPU0_PE3_OCP_TXN<14>
J 0
(-6840 1860);
DISPLAY 0.659574 (-6840 1860);
PAINT MONO (-6840 1860);
DISPLAY INVISIBLE (-6840 1860);
FORCEPROP 1 LASTPIN (-6850 1850) BN 14
R 1
J 0
(-6857 1838);
DISPLAY 0.617021 (-6857 1838);
PAINT GREEN (-6857 1838);
FORCEPROP 2 LAST CDS_LIB mstr_standard
J 0
(-6850 1900);
PAINT ORANGE (-6850 1900);
DISPLAY INVISIBLE (-6850 1900);
FORCEPROP 1 LAST BODY_TYPE PLUMBING
J 0
(-6800 1850);
DISPLAY 2.276596 (-6800 1850);
PAINT GREEN (-6800 1850);
DISPLAY INVISIBLE (-6800 1850);
FORCEPROP 1 LAST HDL_TAP TRUE
J 0
(-6530 1770);
DISPLAY 2.276596 (-6530 1770);
PAINT GREEN (-6530 1770);
DISPLAY INVISIBLE (-6530 1770);
FORCEPROP 1 LAST PATH I113
J 0
(-6852 1900);
DISPLAY 0.872340 (-6852 1900);
PAINT GREEN (-6852 1900);
DISPLAY INVISIBLE (-6852 1900);
FORCEADD CAP..1
R 2
(-6850 1650);
FORCEPROP 1 LAST LOCATION C1M9
J 2
(-6900 1750);
DISPLAY 0.617021 (-6900 1750);
PAINT AQUA (-6900 1750);
FORCEPROP 1 LAST PART_NUMBER A36096-155
J 2
(-6900 1500);
DISPLAY 0.617021 (-6900 1500);
PAINT BLUE (-6900 1500);
FORCEPROP 1 LAST VALUE 0.22UF
J 2
(-6900 1700);
DISPLAY 0.617021 (-6900 1700);
PAINT SKYBLUE (-6900 1700);
FORCEPROP 1 LAST TOLERANCE 10%
J 2
(-6900 1600);
DISPLAY 0.617021 (-6900 1600);
PAINT SKYBLUE (-6900 1600);
FORCEPROP 1 LAST PACK_TYPE 0402
J 2
(-6900 1450);
DISPLAY 0.617021 (-6900 1450);
PAINT SKYBLUE (-6900 1450);
FORCEPROP 1 LAST VOLTAGE 16V
J 2
(-6900 1650);
DISPLAY 0.617021 (-6900 1650);
PAINT SKYBLUE (-6900 1650);
FORCEPROP 1 LAST MATERIAL X7R
J 2
(-6900 1550);
DISPLAY 0.617021 (-6900 1550);
PAINT SKYBLUE (-6900 1550);
FORCEPROP 2 LAST CDS_LIB mstr_discrete
J 0
(-6850 1650);
PAINT ORANGE (-6850 1650);
DISPLAY INVISIBLE (-6850 1650);
FORCEPROP 0 LAST CDS_SEC 1
J 0
(-6900 1800);
PAINT ORANGE (-6900 1800);
DISPLAY INVISIBLE (-6900 1800);
FORCEPROP 2 LAST $SEC 1
J 0
(-6900 1850);
DISPLAY 0.680851 (-6900 1850);
PAINT MONO (-6900 1850);
DISPLAY INVISIBLE (-6900 1850);
FORCEPROP 2 LAST CDS_LOCATION C1M9
J 2
(-6900 1750);
DISPLAY 0.617021 (-6900 1750);
PAINT AQUA (-6900 1750);
DISPLAY INVISIBLE (-6900 1750);
FORCEPROP 1 LAST PATH I114
J 2
(-6900 1800);
DISPLAY 0.978723 (-6900 1800);
PAINT WHITE (-6900 1800);
DISPLAY INVISIBLE (-6900 1800);
FORCEPROP 2 LAST ROOM PCIE_STEERING
J 2
(-6850 1650);
PAINT MONO (-6850 1650);
DISPLAY INVISIBLE (-6850 1650);
FORCEPROP 1 LASTPIN (-6850 1550) $PN 2
J 2
(-6860 1530);
DISPLAY 0.787234 (-6860 1530);
PAINT ORANGE (-6860 1530);
DISPLAY INVISIBLE (-6860 1530);
FORCEPROP 1 LASTPIN (-6850 1750) $PN 1
J 2
(-6860 1730);
DISPLAY 0.787234 (-6860 1730);
PAINT ORANGE (-6860 1730);
DISPLAY INVISIBLE (-6860 1730);
FORCEADD TAP..7
(-6450 1100);
FORCEPROP 3 LASTPIN (-6450 1150) SIG_NAME P3E_OCP_CPU0_PE3_C_TXN<12>
J 0
(-6440 1160);
DISPLAY 0.659574 (-6440 1160);
PAINT MONO (-6440 1160);
DISPLAY INVISIBLE (-6440 1160);
FORCEPROP 1 LASTPIN (-6450 1150) BN 12
R 1
J 0
(-6457 1098);
DISPLAY 0.617021 (-6457 1098);
PAINT GREEN (-6457 1098);
FORCEPROP 2 LAST CDS_LIB mstr_standard
J 0
(-6450 1100);
PAINT ORANGE (-6450 1100);
DISPLAY INVISIBLE (-6450 1100);
FORCEPROP 1 LAST BODY_TYPE PLUMBING
J 0
(-6400 1100);
DISPLAY 2.276596 (-6400 1100);
PAINT GREEN (-6400 1100);
DISPLAY INVISIBLE (-6400 1100);
FORCEPROP 1 LAST HDL_TAP TRUE
J 0
(-6130 970);
DISPLAY 2.276596 (-6130 970);
PAINT GREEN (-6130 970);
DISPLAY INVISIBLE (-6130 970);
FORCEPROP 1 LAST PATH I115
J 0
(-6452 1100);
DISPLAY 0.872340 (-6452 1100);
PAINT GREEN (-6452 1100);
DISPLAY INVISIBLE (-6452 1100);
FORCEADD TAP..7
(-6650 1100);
FORCEPROP 3 LASTPIN (-6650 1150) SIG_NAME P3E_OCP_CPU0_PE3_C_TXN<13>
J 0
(-6640 1160);
DISPLAY 0.659574 (-6640 1160);
PAINT MONO (-6640 1160);
DISPLAY INVISIBLE (-6640 1160);
FORCEPROP 1 LASTPIN (-6650 1150) BN 13
R 1
J 0
(-6657 1098);
DISPLAY 0.617021 (-6657 1098);
PAINT GREEN (-6657 1098);
FORCEPROP 2 LAST CDS_LIB mstr_standard
J 0
(-6650 1100);
PAINT ORANGE (-6650 1100);
DISPLAY INVISIBLE (-6650 1100);
FORCEPROP 1 LAST BODY_TYPE PLUMBING
J 0
(-6600 1100);
DISPLAY 2.276596 (-6600 1100);
PAINT GREEN (-6600 1100);
DISPLAY INVISIBLE (-6600 1100);
FORCEPROP 1 LAST HDL_TAP TRUE
J 0
(-6330 970);
DISPLAY 2.276596 (-6330 970);
PAINT GREEN (-6330 970);
DISPLAY INVISIBLE (-6330 970);
FORCEPROP 1 LAST PATH I116
J 0
(-6652 1100);
DISPLAY 0.872340 (-6652 1100);
PAINT GREEN (-6652 1100);
DISPLAY INVISIBLE (-6652 1100);
FORCEADD CAP..1
R 2
(-6650 1350);
FORCEPROP 1 LAST LOCATION C1M11
J 2
(-6700 1450);
DISPLAY 0.617021 (-6700 1450);
PAINT AQUA (-6700 1450);
FORCEPROP 1 LAST PART_NUMBER A36096-155
J 2
(-6700 1200);
DISPLAY 0.617021 (-6700 1200);
PAINT BLUE (-6700 1200);
FORCEPROP 1 LAST VALUE 0.22UF
J 2
(-6700 1400);
DISPLAY 0.617021 (-6700 1400);
PAINT SKYBLUE (-6700 1400);
FORCEPROP 1 LAST TOLERANCE 10%
J 2
(-6700 1300);
DISPLAY 0.617021 (-6700 1300);
PAINT SKYBLUE (-6700 1300);
FORCEPROP 1 LAST PACK_TYPE 0402
J 2
(-6700 1150);
DISPLAY 0.617021 (-6700 1150);
PAINT SKYBLUE (-6700 1150);
FORCEPROP 1 LAST VOLTAGE 16V
J 2
(-6700 1350);
DISPLAY 0.617021 (-6700 1350);
PAINT SKYBLUE (-6700 1350);
FORCEPROP 1 LAST MATERIAL X7R
J 2
(-6700 1250);
DISPLAY 0.617021 (-6700 1250);
PAINT SKYBLUE (-6700 1250);
FORCEPROP 2 LAST CDS_LIB mstr_discrete
J 0
(-6650 1350);
PAINT ORANGE (-6650 1350);
DISPLAY INVISIBLE (-6650 1350);
FORCEPROP 2 LAST BOM_COST IO_SLOT
J 0
(-6900 1500);
PAINT MONO (-6900 1500);
DISPLAY INVISIBLE (-6900 1500);
FORCEPROP 0 LAST CDS_SEC 1
J 0
(-6700 1500);
PAINT ORANGE (-6700 1500);
DISPLAY INVISIBLE (-6700 1500);
FORCEPROP 2 LAST $SEC 1
J 0
(-6700 1550);
DISPLAY 0.680851 (-6700 1550);
PAINT MONO (-6700 1550);
DISPLAY INVISIBLE (-6700 1550);
FORCEPROP 2 LAST CDS_LOCATION C1M11
J 2
(-6700 1450);
DISPLAY 0.617021 (-6700 1450);
PAINT AQUA (-6700 1450);
DISPLAY INVISIBLE (-6700 1450);
FORCEPROP 1 LAST PATH I117
J 2
(-6700 1500);
DISPLAY 0.978723 (-6700 1500);
PAINT WHITE (-6700 1500);
DISPLAY INVISIBLE (-6700 1500);
FORCEPROP 2 LAST ROOM PCIE_STEERING
J 2
(-6650 1350);
PAINT MONO (-6650 1350);
DISPLAY INVISIBLE (-6650 1350);
FORCEPROP 1 LASTPIN (-6650 1250) $PN 2
J 2
(-6660 1230);
DISPLAY 0.787234 (-6660 1230);
PAINT ORANGE (-6660 1230);
DISPLAY INVISIBLE (-6660 1230);
FORCEPROP 1 LASTPIN (-6650 1450) $PN 1
J 2
(-6660 1430);
DISPLAY 0.787234 (-6660 1430);
PAINT ORANGE (-6660 1430);
DISPLAY INVISIBLE (-6660 1430);
FORCEADD TAP..7
(-6850 1100);
FORCEPROP 3 LASTPIN (-6850 1150) SIG_NAME P3E_OCP_CPU0_PE3_C_TXN<14>
J 0
(-6840 1160);
DISPLAY 0.659574 (-6840 1160);
PAINT MONO (-6840 1160);
DISPLAY INVISIBLE (-6840 1160);
FORCEPROP 1 LASTPIN (-6850 1150) BN 14
R 1
J 0
(-6857 1098);
DISPLAY 0.617021 (-6857 1098);
PAINT GREEN (-6857 1098);
FORCEPROP 2 LAST CDS_LIB mstr_standard
J 0
(-6850 1100);
PAINT ORANGE (-6850 1100);
DISPLAY INVISIBLE (-6850 1100);
FORCEPROP 1 LAST BODY_TYPE PLUMBING
J 0
(-6800 1100);
DISPLAY 2.276596 (-6800 1100);
PAINT GREEN (-6800 1100);
DISPLAY INVISIBLE (-6800 1100);
FORCEPROP 1 LAST HDL_TAP TRUE
J 0
(-6530 970);
DISPLAY 2.276596 (-6530 970);
PAINT GREEN (-6530 970);
DISPLAY INVISIBLE (-6530 970);
FORCEPROP 1 LAST PATH I118
J 0
(-6852 1100);
DISPLAY 0.872340 (-6852 1100);
PAINT GREEN (-6852 1100);
DISPLAY INVISIBLE (-6852 1100);
FORCEADD TAP..3
(-7050 1900);
FORCEPROP 3 LASTPIN (-7050 1850) SIG_NAME P3E_CPU0_PE3_OCP_TXN<15>
J 0
(-7040 1860);
DISPLAY 0.659574 (-7040 1860);
PAINT MONO (-7040 1860);
DISPLAY INVISIBLE (-7040 1860);
FORCEPROP 1 LASTPIN (-7050 1850) BN 15
R 1
J 0
(-7057 1838);
DISPLAY 0.617021 (-7057 1838);
PAINT GREEN (-7057 1838);
FORCEPROP 2 LAST CDS_LIB mstr_standard
J 0
(-7050 1900);
PAINT ORANGE (-7050 1900);
DISPLAY INVISIBLE (-7050 1900);
FORCEPROP 1 LAST BODY_TYPE PLUMBING
J 0
(-7000 1850);
DISPLAY 2.276596 (-7000 1850);
PAINT GREEN (-7000 1850);
DISPLAY INVISIBLE (-7000 1850);
FORCEPROP 1 LAST HDL_TAP TRUE
J 0
(-6730 1770);
DISPLAY 2.276596 (-6730 1770);
PAINT GREEN (-6730 1770);
DISPLAY INVISIBLE (-6730 1770);
FORCEPROP 1 LAST PATH I119
J 0
(-7052 1900);
DISPLAY 0.872340 (-7052 1900);
PAINT GREEN (-7052 1900);
DISPLAY INVISIBLE (-7052 1900);
FORCEADD OFFPAGE..1
(-7225 1950);
FORCEPROP 2 LAST $XR0 32 
J 0
(-7446 1950);
DISPLAY 0.638298 (-7446 1950);
PAINT MONO (-7446 1950);
FORCEPROP 2 LAST CDS_LIB mstr_standard
J 0
(-7225 1950);
PAINT ORANGE (-7225 1950);
DISPLAY INVISIBLE (-7225 1950);
FORCEPROP 1 LAST OFFPAGE TRUE
J 0
(-6905 1820);
PAINT GREEN (-6905 1820);
DISPLAY INVISIBLE (-6905 1820);
FORCEPROP 1 LAST COMMENT_BODY TRUE
J 0
(-7105 1850);
DISPLAY 2.276596 (-7105 1850);
PAINT GREEN (-7105 1850);
DISPLAY INVISIBLE (-7105 1850);
FORCEPROP 2 LAST PATH I120
J 0
(-7475 2000);
DISPLAY 1.021277 (-7475 2000);
PAINT ORANGE (-7475 2000);
DISPLAY INVISIBLE (-7475 2000);
FORCEADD TAP..7
(-7050 1100);
FORCEPROP 3 LASTPIN (-7050 1150) SIG_NAME P3E_OCP_CPU0_PE3_C_TXN<15>
J 0
(-7040 1160);
DISPLAY 0.659574 (-7040 1160);
PAINT MONO (-7040 1160);
DISPLAY INVISIBLE (-7040 1160);
FORCEPROP 1 LASTPIN (-7050 1150) BN 15
R 1
J 0
(-7057 1098);
DISPLAY 0.617021 (-7057 1098);
PAINT GREEN (-7057 1098);
FORCEPROP 2 LAST CDS_LIB mstr_standard
J 0
(-7050 1100);
PAINT ORANGE (-7050 1100);
DISPLAY INVISIBLE (-7050 1100);
FORCEPROP 1 LAST BODY_TYPE PLUMBING
J 0
(-7000 1100);
DISPLAY 2.276596 (-7000 1100);
PAINT GREEN (-7000 1100);
DISPLAY INVISIBLE (-7000 1100);
FORCEPROP 1 LAST HDL_TAP TRUE
J 0
(-6730 970);
DISPLAY 2.276596 (-6730 970);
PAINT GREEN (-6730 970);
DISPLAY INVISIBLE (-6730 970);
FORCEPROP 1 LAST PATH I121
J 0
(-7052 1100);
DISPLAY 0.872340 (-7052 1100);
PAINT GREEN (-7052 1100);
DISPLAY INVISIBLE (-7052 1100);
FORCEADD CAP..1
R 2
(-7050 1350);
FORCEPROP 1 LAST LOCATION C1M7
J 2
(-7100 1450);
DISPLAY 0.617021 (-7100 1450);
PAINT AQUA (-7100 1450);
FORCEPROP 1 LAST PART_NUMBER A36096-155
J 2
(-7100 1200);
DISPLAY 0.617021 (-7100 1200);
PAINT BLUE (-7100 1200);
FORCEPROP 1 LAST VALUE 0.22UF
J 2
(-7100 1400);
DISPLAY 0.617021 (-7100 1400);
PAINT SKYBLUE (-7100 1400);
FORCEPROP 1 LAST TOLERANCE 10%
J 2
(-7100 1300);
DISPLAY 0.617021 (-7100 1300);
PAINT SKYBLUE (-7100 1300);
FORCEPROP 1 LAST PACK_TYPE 0402
J 2
(-7100 1150);
DISPLAY 0.617021 (-7100 1150);
PAINT SKYBLUE (-7100 1150);
FORCEPROP 1 LAST VOLTAGE 16V
J 2
(-7100 1350);
DISPLAY 0.617021 (-7100 1350);
PAINT SKYBLUE (-7100 1350);
FORCEPROP 1 LAST MATERIAL X7R
J 2
(-7100 1250);
DISPLAY 0.617021 (-7100 1250);
PAINT SKYBLUE (-7100 1250);
FORCEPROP 2 LAST CDS_LIB mstr_discrete
J 0
(-7050 1350);
PAINT ORANGE (-7050 1350);
DISPLAY INVISIBLE (-7050 1350);
FORCEPROP 0 LAST CDS_SEC 1
J 0
(-7100 1500);
PAINT ORANGE (-7100 1500);
DISPLAY INVISIBLE (-7100 1500);
FORCEPROP 2 LAST $SEC 1
J 0
(-7100 1550);
DISPLAY 0.680851 (-7100 1550);
PAINT MONO (-7100 1550);
DISPLAY INVISIBLE (-7100 1550);
FORCEPROP 2 LAST CDS_LOCATION C1M7
J 2
(-7100 1450);
DISPLAY 0.617021 (-7100 1450);
PAINT AQUA (-7100 1450);
DISPLAY INVISIBLE (-7100 1450);
FORCEPROP 1 LAST PATH I122
J 2
(-7100 1500);
DISPLAY 0.978723 (-7100 1500);
PAINT WHITE (-7100 1500);
DISPLAY INVISIBLE (-7100 1500);
FORCEPROP 2 LAST ROOM PCIE_STEERING
J 2
(-7050 1350);
PAINT MONO (-7050 1350);
DISPLAY INVISIBLE (-7050 1350);
FORCEPROP 1 LASTPIN (-7050 1250) $PN 2
J 2
(-7060 1230);
DISPLAY 0.787234 (-7060 1230);
PAINT ORANGE (-7060 1230);
DISPLAY INVISIBLE (-7060 1230);
FORCEPROP 1 LASTPIN (-7050 1450) $PN 1
J 2
(-7060 1430);
DISPLAY 0.787234 (-7060 1430);
PAINT ORANGE (-7060 1430);
DISPLAY INVISIBLE (-7060 1430);
FORCEADD CAP..1
R 2
(-5275 1650);
FORCEPROP 1 LAST LOCATION C2R7
J 2
(-5325 1750);
DISPLAY 0.617021 (-5325 1750);
PAINT AQUA (-5325 1750);
FORCEPROP 1 LAST PART_NUMBER A36096-155
J 2
(-5325 1500);
DISPLAY 0.617021 (-5325 1500);
PAINT BLUE (-5325 1500);
FORCEPROP 1 LAST VALUE 0.22UF
J 2
(-5325 1700);
DISPLAY 0.617021 (-5325 1700);
PAINT SKYBLUE (-5325 1700);
FORCEPROP 1 LAST TOLERANCE 10%
J 2
(-5325 1600);
DISPLAY 0.617021 (-5325 1600);
PAINT SKYBLUE (-5325 1600);
FORCEPROP 1 LAST PACK_TYPE 0402
J 2
(-5325 1450);
DISPLAY 0.617021 (-5325 1450);
PAINT SKYBLUE (-5325 1450);
FORCEPROP 1 LAST VOLTAGE 16V
J 2
(-5325 1650);
DISPLAY 0.617021 (-5325 1650);
PAINT SKYBLUE (-5325 1650);
FORCEPROP 1 LAST MATERIAL X7R
J 2
(-5325 1550);
DISPLAY 0.617021 (-5325 1550);
PAINT SKYBLUE (-5325 1550);
FORCEPROP 2 LAST CDS_LIB mstr_discrete
J 0
(-5275 1650);
PAINT ORANGE (-5275 1650);
DISPLAY INVISIBLE (-5275 1650);
FORCEPROP 2 LAST BOM_COST IO_SLOT
J 0
(-5525 1800);
PAINT MONO (-5525 1800);
DISPLAY INVISIBLE (-5525 1800);
FORCEPROP 0 LAST CDS_SEC 1
J 0
(-5325 1800);
PAINT ORANGE (-5325 1800);
DISPLAY INVISIBLE (-5325 1800);
FORCEPROP 2 LAST $SEC 1
J 0
(-5325 1850);
DISPLAY 0.680851 (-5325 1850);
PAINT MONO (-5325 1850);
DISPLAY INVISIBLE (-5325 1850);
FORCEPROP 2 LAST CDS_LOCATION C2R7
J 2
(-5325 1750);
DISPLAY 0.617021 (-5325 1750);
PAINT AQUA (-5325 1750);
DISPLAY INVISIBLE (-5325 1750);
FORCEPROP 1 LAST PATH I123
J 2
(-5325 1800);
DISPLAY 0.978723 (-5325 1800);
PAINT WHITE (-5325 1800);
DISPLAY INVISIBLE (-5325 1800);
FORCEPROP 2 LAST ROOM PCIE_STEERING
J 2
(-5275 1650);
PAINT MONO (-5275 1650);
DISPLAY INVISIBLE (-5275 1650);
FORCEPROP 1 LASTPIN (-5275 1550) $PN 2
J 2
(-5285 1530);
DISPLAY 0.787234 (-5285 1530);
PAINT ORANGE (-5285 1530);
DISPLAY INVISIBLE (-5285 1530);
FORCEPROP 1 LASTPIN (-5275 1750) $PN 1
J 2
(-5285 1730);
DISPLAY 0.787234 (-5285 1730);
PAINT ORANGE (-5285 1730);
DISPLAY INVISIBLE (-5285 1730);
FORCEADD TAP..7
(-5300 2100);
FORCEPROP 3 LASTPIN (-5300 2150) SIG_NAME P3E_OCP_CPU0_PE3_C_TXP<6>
J 0
(-5290 2160);
DISPLAY 0.659574 (-5290 2160);
PAINT MONO (-5290 2160);
DISPLAY INVISIBLE (-5290 2160);
FORCEPROP 1 LASTPIN (-5300 2150) BN 6
R 1
J 0
(-5307 2098);
DISPLAY 0.617021 (-5307 2098);
PAINT GREEN (-5307 2098);
FORCEPROP 2 LAST CDS_LIB mstr_standard
J 0
(-5300 2100);
PAINT ORANGE (-5300 2100);
DISPLAY INVISIBLE (-5300 2100);
FORCEPROP 1 LAST BODY_TYPE PLUMBING
J 0
(-5250 2100);
DISPLAY 2.276596 (-5250 2100);
PAINT GREEN (-5250 2100);
DISPLAY INVISIBLE (-5250 2100);
FORCEPROP 1 LAST HDL_TAP TRUE
J 0
(-4980 1970);
DISPLAY 2.276596 (-4980 1970);
PAINT GREEN (-4980 1970);
DISPLAY INVISIBLE (-4980 1970);
FORCEPROP 1 LAST PATH I124
J 0
(-5302 2100);
DISPLAY 0.872340 (-5302 2100);
PAINT GREEN (-5302 2100);
DISPLAY INVISIBLE (-5302 2100);
FORCEADD TAP..3
(-5500 2900);
FORCEPROP 3 LASTPIN (-5500 2850) SIG_NAME P3E_CPU0_PE3_OCP_TXP<7>
J 0
(-5490 2860);
DISPLAY 0.659574 (-5490 2860);
PAINT MONO (-5490 2860);
DISPLAY INVISIBLE (-5490 2860);
FORCEPROP 1 LASTPIN (-5500 2850) BN 7
R 1
J 0
(-5507 2838);
DISPLAY 0.617021 (-5507 2838);
PAINT GREEN (-5507 2838);
FORCEPROP 2 LAST CDS_LIB mstr_standard
J 0
(-5500 2900);
PAINT ORANGE (-5500 2900);
DISPLAY INVISIBLE (-5500 2900);
FORCEPROP 1 LAST BODY_TYPE PLUMBING
J 0
(-5450 2850);
DISPLAY 2.276596 (-5450 2850);
PAINT GREEN (-5450 2850);
DISPLAY INVISIBLE (-5450 2850);
FORCEPROP 1 LAST HDL_TAP TRUE
J 0
(-5180 2770);
DISPLAY 2.276596 (-5180 2770);
PAINT GREEN (-5180 2770);
DISPLAY INVISIBLE (-5180 2770);
FORCEPROP 1 LAST PATH I125
J 0
(-5502 2900);
DISPLAY 0.872340 (-5502 2900);
PAINT GREEN (-5502 2900);
DISPLAY INVISIBLE (-5502 2900);
FORCEADD TAP..3
(-4900 2900);
FORCEPROP 3 LASTPIN (-4900 2850) SIG_NAME P3E_CPU0_PE3_OCP_TXP<4>
J 0
(-4890 2860);
DISPLAY 0.659574 (-4890 2860);
PAINT MONO (-4890 2860);
DISPLAY INVISIBLE (-4890 2860);
FORCEPROP 1 LASTPIN (-4900 2850) BN 4
R 1
J 0
(-4907 2838);
DISPLAY 0.617021 (-4907 2838);
PAINT GREEN (-4907 2838);
FORCEPROP 2 LAST CDS_LIB mstr_standard
J 0
(-4900 2900);
PAINT ORANGE (-4900 2900);
DISPLAY INVISIBLE (-4900 2900);
FORCEPROP 1 LAST BODY_TYPE PLUMBING
J 0
(-4850 2850);
DISPLAY 2.276596 (-4850 2850);
PAINT GREEN (-4850 2850);
DISPLAY INVISIBLE (-4850 2850);
FORCEPROP 1 LAST HDL_TAP TRUE
J 0
(-4580 2770);
DISPLAY 2.276596 (-4580 2770);
PAINT GREEN (-4580 2770);
DISPLAY INVISIBLE (-4580 2770);
FORCEPROP 1 LAST PATH I126
J 0
(-4902 2900);
DISPLAY 0.872340 (-4902 2900);
PAINT GREEN (-4902 2900);
DISPLAY INVISIBLE (-4902 2900);
FORCEADD TAP..3
(-5100 2900);
FORCEPROP 3 LASTPIN (-5100 2850) SIG_NAME P3E_CPU0_PE3_OCP_TXP<5>
J 0
(-5090 2860);
DISPLAY 0.659574 (-5090 2860);
PAINT MONO (-5090 2860);
DISPLAY INVISIBLE (-5090 2860);
FORCEPROP 1 LASTPIN (-5100 2850) BN 5
R 1
J 0
(-5107 2838);
DISPLAY 0.617021 (-5107 2838);
PAINT GREEN (-5107 2838);
FORCEPROP 2 LAST CDS_LIB mstr_standard
J 0
(-5100 2900);
PAINT ORANGE (-5100 2900);
DISPLAY INVISIBLE (-5100 2900);
FORCEPROP 1 LAST BODY_TYPE PLUMBING
J 0
(-5050 2850);
DISPLAY 2.276596 (-5050 2850);
PAINT GREEN (-5050 2850);
DISPLAY INVISIBLE (-5050 2850);
FORCEPROP 1 LAST HDL_TAP TRUE
J 0
(-4780 2770);
DISPLAY 2.276596 (-4780 2770);
PAINT GREEN (-4780 2770);
DISPLAY INVISIBLE (-4780 2770);
FORCEPROP 1 LAST PATH I127
J 0
(-5102 2900);
DISPLAY 0.872340 (-5102 2900);
PAINT GREEN (-5102 2900);
DISPLAY INVISIBLE (-5102 2900);
FORCEADD CAP..1
R 2
(-4900 2650);
FORCEPROP 1 LAST LOCATION C1R10
J 2
(-4950 2750);
DISPLAY 0.617021 (-4950 2750);
PAINT AQUA (-4950 2750);
FORCEPROP 1 LAST PART_NUMBER A36096-155
J 2
(-4950 2500);
DISPLAY 0.617021 (-4950 2500);
PAINT BLUE (-4950 2500);
FORCEPROP 1 LAST VALUE 0.22UF
J 2
(-4950 2700);
DISPLAY 0.617021 (-4950 2700);
PAINT SKYBLUE (-4950 2700);
FORCEPROP 1 LAST TOLERANCE 10%
J 2
(-4950 2600);
DISPLAY 0.617021 (-4950 2600);
PAINT SKYBLUE (-4950 2600);
FORCEPROP 1 LAST PACK_TYPE 0402
J 2
(-4950 2450);
DISPLAY 0.617021 (-4950 2450);
PAINT SKYBLUE (-4950 2450);
FORCEPROP 1 LAST VOLTAGE 16V
J 2
(-4950 2650);
DISPLAY 0.617021 (-4950 2650);
PAINT SKYBLUE (-4950 2650);
FORCEPROP 1 LAST MATERIAL X7R
J 2
(-4950 2550);
DISPLAY 0.617021 (-4950 2550);
PAINT SKYBLUE (-4950 2550);
FORCEPROP 2 LAST CDS_LIB mstr_discrete
J 0
(-4900 2650);
PAINT ORANGE (-4900 2650);
DISPLAY INVISIBLE (-4900 2650);
FORCEPROP 2 LAST BOM_COST IO_SLOT
J 0
(-5150 2800);
PAINT MONO (-5150 2800);
DISPLAY INVISIBLE (-5150 2800);
FORCEPROP 0 LAST CDS_SEC 1
J 0
(-4950 2800);
PAINT ORANGE (-4950 2800);
DISPLAY INVISIBLE (-4950 2800);
FORCEPROP 2 LAST $SEC 1
J 0
(-4950 2850);
DISPLAY 0.680851 (-4950 2850);
PAINT MONO (-4950 2850);
DISPLAY INVISIBLE (-4950 2850);
FORCEPROP 2 LAST CDS_LOCATION C1R10
J 2
(-4950 2750);
DISPLAY 0.617021 (-4950 2750);
PAINT AQUA (-4950 2750);
DISPLAY INVISIBLE (-4950 2750);
FORCEPROP 1 LAST PATH I128
J 2
(-4950 2800);
DISPLAY 0.978723 (-4950 2800);
PAINT WHITE (-4950 2800);
DISPLAY INVISIBLE (-4950 2800);
FORCEPROP 2 LAST ROOM PCIE_STEERING
J 2
(-4900 2650);
PAINT MONO (-4900 2650);
DISPLAY INVISIBLE (-4900 2650);
FORCEPROP 1 LASTPIN (-4900 2550) $PN 2
J 2
(-4910 2530);
DISPLAY 0.787234 (-4910 2530);
PAINT ORANGE (-4910 2530);
DISPLAY INVISIBLE (-4910 2530);
FORCEPROP 1 LASTPIN (-4900 2750) $PN 1
J 2
(-4910 2730);
DISPLAY 0.787234 (-4910 2730);
PAINT ORANGE (-4910 2730);
DISPLAY INVISIBLE (-4910 2730);
FORCEADD TAP..7
(-4900 2100);
FORCEPROP 3 LASTPIN (-4900 2150) SIG_NAME P3E_OCP_CPU0_PE3_C_TXP<4>
J 0
(-4890 2160);
DISPLAY 0.659574 (-4890 2160);
PAINT MONO (-4890 2160);
DISPLAY INVISIBLE (-4890 2160);
FORCEPROP 1 LASTPIN (-4900 2150) BN 4
R 1
J 0
(-4907 2098);
DISPLAY 0.617021 (-4907 2098);
PAINT GREEN (-4907 2098);
FORCEPROP 2 LAST CDS_LIB mstr_standard
J 0
(-4900 2100);
PAINT ORANGE (-4900 2100);
DISPLAY INVISIBLE (-4900 2100);
FORCEPROP 1 LAST BODY_TYPE PLUMBING
J 0
(-4850 2100);
DISPLAY 2.276596 (-4850 2100);
PAINT GREEN (-4850 2100);
DISPLAY INVISIBLE (-4850 2100);
FORCEPROP 1 LAST HDL_TAP TRUE
J 0
(-4580 1970);
DISPLAY 2.276596 (-4580 1970);
PAINT GREEN (-4580 1970);
DISPLAY INVISIBLE (-4580 1970);
FORCEPROP 1 LAST PATH I129
J 0
(-4902 2100);
DISPLAY 0.872340 (-4902 2100);
PAINT GREEN (-4902 2100);
DISPLAY INVISIBLE (-4902 2100);
FORCEADD CAP..1
R 2
(-5100 2350);
FORCEPROP 1 LAST LOCATION C2R14
J 2
(-5150 2450);
DISPLAY 0.617021 (-5150 2450);
PAINT AQUA (-5150 2450);
FORCEPROP 1 LAST PART_NUMBER A36096-155
J 2
(-5150 2200);
DISPLAY 0.617021 (-5150 2200);
PAINT BLUE (-5150 2200);
FORCEPROP 1 LAST VALUE 0.22UF
J 2
(-5150 2400);
DISPLAY 0.617021 (-5150 2400);
PAINT SKYBLUE (-5150 2400);
FORCEPROP 1 LAST TOLERANCE 10%
J 2
(-5150 2300);
DISPLAY 0.617021 (-5150 2300);
PAINT SKYBLUE (-5150 2300);
FORCEPROP 1 LAST PACK_TYPE 0402
J 2
(-5150 2150);
DISPLAY 0.617021 (-5150 2150);
PAINT SKYBLUE (-5150 2150);
FORCEPROP 1 LAST VOLTAGE 16V
J 2
(-5150 2350);
DISPLAY 0.617021 (-5150 2350);
PAINT SKYBLUE (-5150 2350);
FORCEPROP 1 LAST MATERIAL X7R
J 2
(-5150 2250);
DISPLAY 0.617021 (-5150 2250);
PAINT SKYBLUE (-5150 2250);
FORCEPROP 2 LAST CDS_LIB mstr_discrete
J 0
(-5100 2350);
PAINT ORANGE (-5100 2350);
DISPLAY INVISIBLE (-5100 2350);
FORCEPROP 2 LAST BOM_COST IO_SLOT
J 0
(-5350 2500);
PAINT MONO (-5350 2500);
DISPLAY INVISIBLE (-5350 2500);
FORCEPROP 0 LAST CDS_SEC 1
J 0
(-5150 2500);
PAINT ORANGE (-5150 2500);
DISPLAY INVISIBLE (-5150 2500);
FORCEPROP 2 LAST $SEC 1
J 0
(-5150 2550);
DISPLAY 0.680851 (-5150 2550);
PAINT MONO (-5150 2550);
DISPLAY INVISIBLE (-5150 2550);
FORCEPROP 1 LAST PATH I130
J 2
(-5150 2500);
DISPLAY 0.978723 (-5150 2500);
PAINT WHITE (-5150 2500);
DISPLAY INVISIBLE (-5150 2500);
FORCEPROP 2 LAST ROOM PCIE_STEERING
J 2
(-5100 2350);
PAINT MONO (-5100 2350);
DISPLAY INVISIBLE (-5100 2350);
FORCEPROP 1 LASTPIN (-5100 2250) $PN 2
J 2
(-5110 2230);
DISPLAY 0.787234 (-5110 2230);
PAINT ORANGE (-5110 2230);
DISPLAY INVISIBLE (-5110 2230);
FORCEPROP 1 LASTPIN (-5100 2450) $PN 1
J 2
(-5110 2430);
DISPLAY 0.787234 (-5110 2430);
PAINT ORANGE (-5110 2430);
DISPLAY INVISIBLE (-5110 2430);
FORCEADD TAP..7
(-5100 2100);
FORCEPROP 3 LASTPIN (-5100 2150) SIG_NAME P3E_OCP_CPU0_PE3_C_TXP<5>
J 0
(-5090 2160);
DISPLAY 0.659574 (-5090 2160);
PAINT MONO (-5090 2160);
DISPLAY INVISIBLE (-5090 2160);
FORCEPROP 1 LASTPIN (-5100 2150) BN 5
R 1
J 0
(-5107 2098);
DISPLAY 0.617021 (-5107 2098);
PAINT GREEN (-5107 2098);
FORCEPROP 2 LAST CDS_LIB mstr_standard
J 0
(-5100 2100);
PAINT ORANGE (-5100 2100);
DISPLAY INVISIBLE (-5100 2100);
FORCEPROP 1 LAST BODY_TYPE PLUMBING
J 0
(-5050 2100);
DISPLAY 2.276596 (-5050 2100);
PAINT GREEN (-5050 2100);
DISPLAY INVISIBLE (-5050 2100);
FORCEPROP 1 LAST HDL_TAP TRUE
J 0
(-4780 1970);
DISPLAY 2.276596 (-4780 1970);
PAINT GREEN (-4780 1970);
DISPLAY INVISIBLE (-4780 1970);
FORCEPROP 1 LAST PATH I131
J 0
(-5102 2100);
DISPLAY 0.872340 (-5102 2100);
PAINT GREEN (-5102 2100);
DISPLAY INVISIBLE (-5102 2100);
FORCEADD TAP..3
(-4875 1900);
FORCEPROP 3 LASTPIN (-4875 1850) SIG_NAME P3E_CPU0_PE3_OCP_TXN<4>
J 0
(-4865 1860);
DISPLAY 0.659574 (-4865 1860);
PAINT MONO (-4865 1860);
DISPLAY INVISIBLE (-4865 1860);
FORCEPROP 1 LASTPIN (-4875 1850) BN 4
R 1
J 0
(-4882 1838);
DISPLAY 0.617021 (-4882 1838);
PAINT GREEN (-4882 1838);
FORCEPROP 2 LAST CDS_LIB mstr_standard
J 0
(-4875 1900);
PAINT ORANGE (-4875 1900);
DISPLAY INVISIBLE (-4875 1900);
FORCEPROP 1 LAST BODY_TYPE PLUMBING
J 0
(-4825 1850);
DISPLAY 2.276596 (-4825 1850);
PAINT GREEN (-4825 1850);
DISPLAY INVISIBLE (-4825 1850);
FORCEPROP 1 LAST HDL_TAP TRUE
J 0
(-4555 1770);
DISPLAY 2.276596 (-4555 1770);
PAINT GREEN (-4555 1770);
DISPLAY INVISIBLE (-4555 1770);
FORCEPROP 1 LAST PATH I133
J 0
(-4877 1900);
DISPLAY 0.872340 (-4877 1900);
PAINT GREEN (-4877 1900);
DISPLAY INVISIBLE (-4877 1900);
FORCEADD CAP..1
R 2
(-4875 1650);
FORCEPROP 1 LAST PART_NUMBER A36096-155
J 2
(-4925 1500);
DISPLAY 0.617021 (-4925 1500);
PAINT BLUE (-4925 1500);
FORCEPROP 1 LAST VALUE 0.22UF
J 2
(-4925 1700);
DISPLAY 0.617021 (-4925 1700);
PAINT SKYBLUE (-4925 1700);
FORCEPROP 1 LAST TOLERANCE 10%
J 2
(-4925 1600);
DISPLAY 0.617021 (-4925 1600);
PAINT SKYBLUE (-4925 1600);
FORCEPROP 1 LAST PACK_TYPE 0402
J 2
(-4925 1450);
DISPLAY 0.617021 (-4925 1450);
PAINT SKYBLUE (-4925 1450);
FORCEPROP 1 LAST VOLTAGE 16V
J 2
(-4925 1650);
DISPLAY 0.617021 (-4925 1650);
PAINT SKYBLUE (-4925 1650);
FORCEPROP 1 LAST MATERIAL X7R
J 2
(-4925 1550);
DISPLAY 0.617021 (-4925 1550);
PAINT SKYBLUE (-4925 1550);
FORCEPROP 1 LAST LOCATION C1R9
J 2
(-4925 1750);
DISPLAY 0.617021 (-4925 1750);
PAINT AQUA (-4925 1750);
FORCEPROP 2 LAST CDS_LIB mstr_discrete
J 0
(-4875 1650);
PAINT ORANGE (-4875 1650);
DISPLAY INVISIBLE (-4875 1650);
FORCEPROP 2 LAST BOM_COST IO_SLOT
J 0
(-5125 1800);
PAINT MONO (-5125 1800);
DISPLAY INVISIBLE (-5125 1800);
FORCEPROP 0 LAST CDS_SEC 1
J 0
(-4925 1800);
PAINT ORANGE (-4925 1800);
DISPLAY INVISIBLE (-4925 1800);
FORCEPROP 2 LAST $SEC 1
J 0
(-4925 1850);
DISPLAY 0.680851 (-4925 1850);
PAINT MONO (-4925 1850);
DISPLAY INVISIBLE (-4925 1850);
FORCEPROP 2 LAST CDS_LOCATION C1R9
J 2
(-4925 1750);
DISPLAY 0.617021 (-4925 1750);
PAINT AQUA (-4925 1750);
DISPLAY INVISIBLE (-4925 1750);
FORCEPROP 1 LAST PATH I134
J 2
(-4925 1800);
DISPLAY 0.978723 (-4925 1800);
PAINT WHITE (-4925 1800);
DISPLAY INVISIBLE (-4925 1800);
FORCEPROP 2 LAST ROOM PCIE_STEERING
J 2
(-4875 1650);
PAINT MONO (-4875 1650);
DISPLAY INVISIBLE (-4875 1650);
FORCEPROP 1 LASTPIN (-4875 1550) $PN 2
J 2
(-4885 1530);
DISPLAY 0.787234 (-4885 1530);
PAINT ORANGE (-4885 1530);
DISPLAY INVISIBLE (-4885 1530);
FORCEPROP 1 LASTPIN (-4875 1750) $PN 1
J 2
(-4885 1730);
DISPLAY 0.787234 (-4885 1730);
PAINT ORANGE (-4885 1730);
DISPLAY INVISIBLE (-4885 1730);
FORCEADD TAP..3
(-5075 1900);
FORCEPROP 3 LASTPIN (-5075 1850) SIG_NAME P3E_CPU0_PE3_OCP_TXN<5>
J 0
(-5065 1860);
DISPLAY 0.659574 (-5065 1860);
PAINT MONO (-5065 1860);
DISPLAY INVISIBLE (-5065 1860);
FORCEPROP 1 LASTPIN (-5075 1850) BN 5
R 1
J 0
(-5082 1838);
DISPLAY 0.617021 (-5082 1838);
PAINT GREEN (-5082 1838);
FORCEPROP 2 LAST CDS_LIB mstr_standard
J 0
(-5075 1900);
PAINT ORANGE (-5075 1900);
DISPLAY INVISIBLE (-5075 1900);
FORCEPROP 1 LAST BODY_TYPE PLUMBING
J 0
(-5025 1850);
DISPLAY 2.276596 (-5025 1850);
PAINT GREEN (-5025 1850);
DISPLAY INVISIBLE (-5025 1850);
FORCEPROP 1 LAST HDL_TAP TRUE
J 0
(-4755 1770);
DISPLAY 2.276596 (-4755 1770);
PAINT GREEN (-4755 1770);
DISPLAY INVISIBLE (-4755 1770);
FORCEPROP 1 LAST PATH I135
J 0
(-5077 1900);
DISPLAY 0.872340 (-5077 1900);
PAINT GREEN (-5077 1900);
DISPLAY INVISIBLE (-5077 1900);
FORCEADD TAP..7
(-4875 1100);
FORCEPROP 3 LASTPIN (-4875 1150) SIG_NAME P3E_OCP_CPU0_PE3_C_TXN<4>
J 0
(-4865 1160);
DISPLAY 0.659574 (-4865 1160);
PAINT MONO (-4865 1160);
DISPLAY INVISIBLE (-4865 1160);
FORCEPROP 1 LASTPIN (-4875 1150) BN 4
R 1
J 0
(-4882 1098);
DISPLAY 0.617021 (-4882 1098);
PAINT GREEN (-4882 1098);
FORCEPROP 2 LAST CDS_LIB mstr_standard
J 0
(-4875 1100);
PAINT ORANGE (-4875 1100);
DISPLAY INVISIBLE (-4875 1100);
FORCEPROP 1 LAST BODY_TYPE PLUMBING
J 0
(-4825 1100);
DISPLAY 2.276596 (-4825 1100);
PAINT GREEN (-4825 1100);
DISPLAY INVISIBLE (-4825 1100);
FORCEPROP 1 LAST HDL_TAP TRUE
J 0
(-4555 970);
DISPLAY 2.276596 (-4555 970);
PAINT GREEN (-4555 970);
DISPLAY INVISIBLE (-4555 970);
FORCEPROP 1 LAST PATH I136
J 0
(-4877 1100);
DISPLAY 0.872340 (-4877 1100);
PAINT GREEN (-4877 1100);
DISPLAY INVISIBLE (-4877 1100);
FORCEADD CAP..1
R 2
(-5075 1350);
FORCEPROP 1 LAST LOCATION C2R13
J 2
(-5125 1450);
DISPLAY 0.617021 (-5125 1450);
PAINT AQUA (-5125 1450);
FORCEPROP 1 LAST PART_NUMBER A36096-155
J 2
(-5125 1200);
DISPLAY 0.617021 (-5125 1200);
PAINT BLUE (-5125 1200);
FORCEPROP 1 LAST VALUE 0.22UF
J 2
(-5125 1400);
DISPLAY 0.617021 (-5125 1400);
PAINT SKYBLUE (-5125 1400);
FORCEPROP 1 LAST TOLERANCE 10%
J 2
(-5125 1300);
DISPLAY 0.617021 (-5125 1300);
PAINT SKYBLUE (-5125 1300);
FORCEPROP 1 LAST PACK_TYPE 0402
J 2
(-5125 1150);
DISPLAY 0.617021 (-5125 1150);
PAINT SKYBLUE (-5125 1150);
FORCEPROP 1 LAST VOLTAGE 16V
J 2
(-5125 1350);
DISPLAY 0.617021 (-5125 1350);
PAINT SKYBLUE (-5125 1350);
FORCEPROP 1 LAST MATERIAL X7R
J 2
(-5125 1250);
DISPLAY 0.617021 (-5125 1250);
PAINT SKYBLUE (-5125 1250);
FORCEPROP 2 LAST CDS_LIB mstr_discrete
J 0
(-5075 1350);
PAINT ORANGE (-5075 1350);
DISPLAY INVISIBLE (-5075 1350);
FORCEPROP 2 LAST BOM_COST IO_SLOT
J 0
(-5325 1500);
PAINT MONO (-5325 1500);
DISPLAY INVISIBLE (-5325 1500);
FORCEPROP 0 LAST CDS_SEC 1
J 0
(-5125 1500);
PAINT ORANGE (-5125 1500);
DISPLAY INVISIBLE (-5125 1500);
FORCEPROP 2 LAST $SEC 1
J 0
(-5125 1550);
DISPLAY 0.680851 (-5125 1550);
PAINT MONO (-5125 1550);
DISPLAY INVISIBLE (-5125 1550);
FORCEPROP 1 LAST PATH I137
J 2
(-5125 1500);
DISPLAY 0.978723 (-5125 1500);
PAINT WHITE (-5125 1500);
DISPLAY INVISIBLE (-5125 1500);
FORCEPROP 2 LAST ROOM PCIE_STEERING
J 2
(-5075 1350);
PAINT MONO (-5075 1350);
DISPLAY INVISIBLE (-5075 1350);
FORCEPROP 1 LASTPIN (-5075 1250) $PN 2
J 2
(-5085 1230);
DISPLAY 0.787234 (-5085 1230);
PAINT ORANGE (-5085 1230);
DISPLAY INVISIBLE (-5085 1230);
FORCEPROP 1 LASTPIN (-5075 1450) $PN 1
J 2
(-5085 1430);
DISPLAY 0.787234 (-5085 1430);
PAINT ORANGE (-5085 1430);
DISPLAY INVISIBLE (-5085 1430);
FORCEADD TAP..7
(-5075 1100);
FORCEPROP 3 LASTPIN (-5075 1150) SIG_NAME P3E_OCP_CPU0_PE3_C_TXN<5>
J 0
(-5065 1160);
DISPLAY 0.659574 (-5065 1160);
PAINT MONO (-5065 1160);
DISPLAY INVISIBLE (-5065 1160);
FORCEPROP 1 LASTPIN (-5075 1150) BN 5
R 1
J 0
(-5082 1098);
DISPLAY 0.617021 (-5082 1098);
PAINT GREEN (-5082 1098);
FORCEPROP 2 LAST CDS_LIB mstr_standard
J 0
(-5075 1100);
PAINT ORANGE (-5075 1100);
DISPLAY INVISIBLE (-5075 1100);
FORCEPROP 1 LAST BODY_TYPE PLUMBING
J 0
(-5025 1100);
DISPLAY 2.276596 (-5025 1100);
PAINT GREEN (-5025 1100);
DISPLAY INVISIBLE (-5025 1100);
FORCEPROP 1 LAST HDL_TAP TRUE
J 0
(-4755 970);
DISPLAY 2.276596 (-4755 970);
PAINT GREEN (-4755 970);
DISPLAY INVISIBLE (-4755 970);
FORCEPROP 1 LAST PATH I138
J 0
(-5077 1100);
DISPLAY 0.872340 (-5077 1100);
PAINT GREEN (-5077 1100);
DISPLAY INVISIBLE (-5077 1100);
FORCEADD TAP..3
(-5300 2900);
FORCEPROP 3 LASTPIN (-5300 2850) SIG_NAME P3E_CPU0_PE3_OCP_TXP<6>
J 0
(-5290 2860);
DISPLAY 0.659574 (-5290 2860);
PAINT MONO (-5290 2860);
DISPLAY INVISIBLE (-5290 2860);
FORCEPROP 1 LASTPIN (-5300 2850) BN 6
R 1
J 0
(-5307 2838);
DISPLAY 0.617021 (-5307 2838);
PAINT GREEN (-5307 2838);
FORCEPROP 2 LAST CDS_LIB mstr_standard
J 0
(-5300 2900);
PAINT ORANGE (-5300 2900);
DISPLAY INVISIBLE (-5300 2900);
FORCEPROP 1 LAST BODY_TYPE PLUMBING
J 0
(-5250 2850);
DISPLAY 2.276596 (-5250 2850);
PAINT GREEN (-5250 2850);
DISPLAY INVISIBLE (-5250 2850);
FORCEPROP 1 LAST HDL_TAP TRUE
J 0
(-4980 2770);
DISPLAY 2.276596 (-4980 2770);
PAINT GREEN (-4980 2770);
DISPLAY INVISIBLE (-4980 2770);
FORCEPROP 1 LAST PATH I140
J 0
(-5302 2900);
DISPLAY 0.872340 (-5302 2900);
PAINT GREEN (-5302 2900);
DISPLAY INVISIBLE (-5302 2900);
FORCEADD CAP..1
R 2
(-5300 2650);
FORCEPROP 1 LAST LOCATION C2R8
J 2
(-5350 2750);
DISPLAY 0.617021 (-5350 2750);
PAINT AQUA (-5350 2750);
FORCEPROP 1 LAST PART_NUMBER A36096-155
J 2
(-5350 2500);
DISPLAY 0.617021 (-5350 2500);
PAINT BLUE (-5350 2500);
FORCEPROP 1 LAST VALUE 0.22UF
J 2
(-5350 2700);
DISPLAY 0.617021 (-5350 2700);
PAINT SKYBLUE (-5350 2700);
FORCEPROP 1 LAST TOLERANCE 10%
J 2
(-5350 2600);
DISPLAY 0.617021 (-5350 2600);
PAINT SKYBLUE (-5350 2600);
FORCEPROP 1 LAST PACK_TYPE 0402
J 2
(-5350 2450);
DISPLAY 0.617021 (-5350 2450);
PAINT SKYBLUE (-5350 2450);
FORCEPROP 1 LAST VOLTAGE 16V
J 2
(-5350 2650);
DISPLAY 0.617021 (-5350 2650);
PAINT SKYBLUE (-5350 2650);
FORCEPROP 1 LAST MATERIAL X7R
J 2
(-5350 2550);
DISPLAY 0.617021 (-5350 2550);
PAINT SKYBLUE (-5350 2550);
FORCEPROP 2 LAST CDS_LIB mstr_discrete
J 0
(-5300 2650);
PAINT ORANGE (-5300 2650);
DISPLAY INVISIBLE (-5300 2650);
FORCEPROP 2 LAST BOM_COST IO_SLOT
J 0
(-5550 2800);
PAINT MONO (-5550 2800);
DISPLAY INVISIBLE (-5550 2800);
FORCEPROP 0 LAST CDS_SEC 1
J 0
(-5350 2800);
PAINT ORANGE (-5350 2800);
DISPLAY INVISIBLE (-5350 2800);
FORCEPROP 2 LAST $SEC 1
J 0
(-5350 2850);
DISPLAY 0.680851 (-5350 2850);
PAINT MONO (-5350 2850);
DISPLAY INVISIBLE (-5350 2850);
FORCEPROP 2 LAST CDS_LOCATION C2R8
J 2
(-5350 2750);
DISPLAY 0.617021 (-5350 2750);
PAINT AQUA (-5350 2750);
DISPLAY INVISIBLE (-5350 2750);
FORCEPROP 1 LAST PATH I141
J 2
(-5350 2800);
DISPLAY 0.978723 (-5350 2800);
PAINT WHITE (-5350 2800);
DISPLAY INVISIBLE (-5350 2800);
FORCEPROP 2 LAST ROOM PCIE_STEERING
J 2
(-5300 2650);
PAINT MONO (-5300 2650);
DISPLAY INVISIBLE (-5300 2650);
FORCEPROP 1 LASTPIN (-5300 2550) $PN 2
J 2
(-5310 2530);
DISPLAY 0.787234 (-5310 2530);
PAINT ORANGE (-5310 2530);
DISPLAY INVISIBLE (-5310 2530);
FORCEPROP 1 LASTPIN (-5300 2750) $PN 1
J 2
(-5310 2730);
DISPLAY 0.787234 (-5310 2730);
PAINT ORANGE (-5310 2730);
DISPLAY INVISIBLE (-5310 2730);
FORCEADD CAP..1
R 2
(-5500 2350);
FORCEPROP 1 LAST LOCATION C2R10
J 2
(-5550 2450);
DISPLAY 0.617021 (-5550 2450);
PAINT AQUA (-5550 2450);
FORCEPROP 1 LAST PART_NUMBER A36096-155
J 2
(-5550 2200);
DISPLAY 0.617021 (-5550 2200);
PAINT BLUE (-5550 2200);
FORCEPROP 1 LAST VALUE 0.22UF
J 2
(-5550 2400);
DISPLAY 0.617021 (-5550 2400);
PAINT SKYBLUE (-5550 2400);
FORCEPROP 1 LAST TOLERANCE 10%
J 2
(-5550 2300);
DISPLAY 0.617021 (-5550 2300);
PAINT SKYBLUE (-5550 2300);
FORCEPROP 1 LAST VOLTAGE 16V
J 2
(-5550 2350);
DISPLAY 0.617021 (-5550 2350);
PAINT SKYBLUE (-5550 2350);
FORCEPROP 1 LAST MATERIAL X7R
J 2
(-5550 2250);
DISPLAY 0.617021 (-5550 2250);
PAINT SKYBLUE (-5550 2250);
FORCEPROP 1 LAST PACK_TYPE 0402
J 2
(-5550 2150);
DISPLAY 0.617021 (-5550 2150);
PAINT SKYBLUE (-5550 2150);
FORCEPROP 2 LAST CDS_LIB mstr_discrete
J 0
(-5500 2350);
PAINT ORANGE (-5500 2350);
DISPLAY INVISIBLE (-5500 2350);
FORCEPROP 2 LAST BOM_COST IO_SLOT
J 0
(-5750 2500);
PAINT MONO (-5750 2500);
DISPLAY INVISIBLE (-5750 2500);
FORCEPROP 0 LAST CDS_SEC 1
J 0
(-5550 2500);
PAINT ORANGE (-5550 2500);
DISPLAY INVISIBLE (-5550 2500);
FORCEPROP 2 LAST $SEC 1
J 0
(-5550 2550);
DISPLAY 0.680851 (-5550 2550);
PAINT MONO (-5550 2550);
DISPLAY INVISIBLE (-5550 2550);
FORCEPROP 2 LAST CDS_LOCATION C2R10
J 2
(-5550 2450);
DISPLAY 0.617021 (-5550 2450);
PAINT AQUA (-5550 2450);
DISPLAY INVISIBLE (-5550 2450);
FORCEPROP 1 LAST PATH I142
J 2
(-5550 2500);
DISPLAY 0.978723 (-5550 2500);
PAINT WHITE (-5550 2500);
DISPLAY INVISIBLE (-5550 2500);
FORCEPROP 2 LAST ROOM PCIE_STEERING
J 2
(-5500 2350);
PAINT MONO (-5500 2350);
DISPLAY INVISIBLE (-5500 2350);
FORCEPROP 1 LASTPIN (-5500 2250) $PN 2
J 2
(-5510 2230);
DISPLAY 0.787234 (-5510 2230);
PAINT ORANGE (-5510 2230);
DISPLAY INVISIBLE (-5510 2230);
FORCEPROP 1 LASTPIN (-5500 2450) $PN 1
J 2
(-5510 2430);
DISPLAY 0.787234 (-5510 2430);
PAINT ORANGE (-5510 2430);
DISPLAY INVISIBLE (-5510 2430);
FORCEADD TAP..7
(-5500 2100);
FORCEPROP 3 LASTPIN (-5500 2150) SIG_NAME P3E_OCP_CPU0_PE3_C_TXP<7>
J 0
(-5490 2160);
DISPLAY 0.659574 (-5490 2160);
PAINT MONO (-5490 2160);
DISPLAY INVISIBLE (-5490 2160);
FORCEPROP 1 LASTPIN (-5500 2150) BN 7
R 1
J 0
(-5507 2098);
DISPLAY 0.617021 (-5507 2098);
PAINT GREEN (-5507 2098);
FORCEPROP 2 LAST CDS_LIB mstr_standard
J 0
(-5500 2100);
PAINT ORANGE (-5500 2100);
DISPLAY INVISIBLE (-5500 2100);
FORCEPROP 1 LAST BODY_TYPE PLUMBING
J 0
(-5450 2100);
DISPLAY 2.276596 (-5450 2100);
PAINT GREEN (-5450 2100);
DISPLAY INVISIBLE (-5450 2100);
FORCEPROP 1 LAST HDL_TAP TRUE
J 0
(-5180 1970);
DISPLAY 2.276596 (-5180 1970);
PAINT GREEN (-5180 1970);
DISPLAY INVISIBLE (-5180 1970);
FORCEPROP 1 LAST PATH I143
J 0
(-5502 2100);
DISPLAY 0.872340 (-5502 2100);
PAINT GREEN (-5502 2100);
DISPLAY INVISIBLE (-5502 2100);
FORCEADD TAP..3
(-5275 1900);
FORCEPROP 3 LASTPIN (-5275 1850) SIG_NAME P3E_CPU0_PE3_OCP_TXN<6>
J 0
(-5265 1860);
DISPLAY 0.659574 (-5265 1860);
PAINT MONO (-5265 1860);
DISPLAY INVISIBLE (-5265 1860);
FORCEPROP 1 LASTPIN (-5275 1850) BN 6
R 1
J 0
(-5282 1838);
DISPLAY 0.617021 (-5282 1838);
PAINT GREEN (-5282 1838);
FORCEPROP 2 LAST CDS_LIB mstr_standard
J 0
(-5275 1900);
PAINT ORANGE (-5275 1900);
DISPLAY INVISIBLE (-5275 1900);
FORCEPROP 1 LAST BODY_TYPE PLUMBING
J 0
(-5225 1850);
DISPLAY 2.276596 (-5225 1850);
PAINT GREEN (-5225 1850);
DISPLAY INVISIBLE (-5225 1850);
FORCEPROP 1 LAST HDL_TAP TRUE
J 0
(-4955 1770);
DISPLAY 1.829787 (-4955 1770);
PAINT GREEN (-4955 1770);
DISPLAY INVISIBLE (-4955 1770);
FORCEPROP 1 LAST PATH I144
J 0
(-5277 1900);
DISPLAY 0.872340 (-5277 1900);
PAINT GREEN (-5277 1900);
DISPLAY INVISIBLE (-5277 1900);
FORCEADD TAP..3
(-5475 1900);
FORCEPROP 3 LASTPIN (-5475 1850) SIG_NAME P3E_CPU0_PE3_OCP_TXN<7>
J 0
(-5465 1860);
DISPLAY 0.659574 (-5465 1860);
PAINT MONO (-5465 1860);
DISPLAY INVISIBLE (-5465 1860);
FORCEPROP 1 LASTPIN (-5475 1850) BN 7
R 1
J 0
(-5482 1838);
DISPLAY 0.617021 (-5482 1838);
PAINT GREEN (-5482 1838);
FORCEPROP 2 LAST CDS_LIB mstr_standard
J 0
(-5475 1900);
PAINT ORANGE (-5475 1900);
DISPLAY INVISIBLE (-5475 1900);
FORCEPROP 1 LAST BODY_TYPE PLUMBING
J 0
(-5425 1850);
DISPLAY 2.276596 (-5425 1850);
PAINT GREEN (-5425 1850);
DISPLAY INVISIBLE (-5425 1850);
FORCEPROP 1 LAST HDL_TAP TRUE
J 0
(-5155 1770);
DISPLAY 2.276596 (-5155 1770);
PAINT GREEN (-5155 1770);
DISPLAY INVISIBLE (-5155 1770);
FORCEPROP 1 LAST PATH I145
J 0
(-5477 1900);
DISPLAY 0.872340 (-5477 1900);
PAINT GREEN (-5477 1900);
DISPLAY INVISIBLE (-5477 1900);
FORCEADD TAP..7
(-5275 1100);
FORCEPROP 3 LASTPIN (-5275 1150) SIG_NAME P3E_OCP_CPU0_PE3_C_TXN<6>
J 0
(-5265 1160);
DISPLAY 0.659574 (-5265 1160);
PAINT MONO (-5265 1160);
DISPLAY INVISIBLE (-5265 1160);
FORCEPROP 1 LASTPIN (-5275 1150) BN 6
R 1
J 0
(-5282 1098);
DISPLAY 0.617021 (-5282 1098);
PAINT GREEN (-5282 1098);
FORCEPROP 2 LAST CDS_LIB mstr_standard
J 0
(-5275 1100);
PAINT ORANGE (-5275 1100);
DISPLAY INVISIBLE (-5275 1100);
FORCEPROP 1 LAST BODY_TYPE PLUMBING
J 0
(-5225 1100);
DISPLAY 2.276596 (-5225 1100);
PAINT GREEN (-5225 1100);
DISPLAY INVISIBLE (-5225 1100);
FORCEPROP 1 LAST HDL_TAP TRUE
J 0
(-4955 970);
DISPLAY 2.276596 (-4955 970);
PAINT GREEN (-4955 970);
DISPLAY INVISIBLE (-4955 970);
FORCEPROP 1 LAST PATH I146
J 0
(-5277 1100);
DISPLAY 0.872340 (-5277 1100);
PAINT GREEN (-5277 1100);
DISPLAY INVISIBLE (-5277 1100);
FORCEADD CAP..1
R 2
(-5475 1350);
FORCEPROP 1 LAST LOCATION C2R9
J 2
(-5525 1450);
DISPLAY 0.617021 (-5525 1450);
PAINT AQUA (-5525 1450);
FORCEPROP 1 LAST PART_NUMBER A36096-155
J 2
(-5525 1200);
DISPLAY 0.617021 (-5525 1200);
PAINT BLUE (-5525 1200);
FORCEPROP 1 LAST VALUE 0.22UF
J 2
(-5525 1400);
DISPLAY 0.617021 (-5525 1400);
PAINT SKYBLUE (-5525 1400);
FORCEPROP 1 LAST TOLERANCE 10%
J 2
(-5525 1300);
DISPLAY 0.617021 (-5525 1300);
PAINT SKYBLUE (-5525 1300);
FORCEPROP 1 LAST PACK_TYPE 0402
J 2
(-5525 1150);
DISPLAY 0.617021 (-5525 1150);
PAINT SKYBLUE (-5525 1150);
FORCEPROP 1 LAST VOLTAGE 16V
J 2
(-5525 1350);
DISPLAY 0.617021 (-5525 1350);
PAINT SKYBLUE (-5525 1350);
FORCEPROP 1 LAST MATERIAL X7R
J 2
(-5525 1250);
DISPLAY 0.617021 (-5525 1250);
PAINT SKYBLUE (-5525 1250);
FORCEPROP 2 LAST CDS_LIB mstr_discrete
J 0
(-5475 1350);
PAINT ORANGE (-5475 1350);
DISPLAY INVISIBLE (-5475 1350);
FORCEPROP 2 LAST BOM_COST IO_SLOT
J 0
(-5725 1500);
PAINT MONO (-5725 1500);
DISPLAY INVISIBLE (-5725 1500);
FORCEPROP 0 LAST CDS_SEC 1
J 0
(-5525 1500);
PAINT ORANGE (-5525 1500);
DISPLAY INVISIBLE (-5525 1500);
FORCEPROP 2 LAST $SEC 1
J 0
(-5525 1550);
DISPLAY 0.680851 (-5525 1550);
PAINT MONO (-5525 1550);
DISPLAY INVISIBLE (-5525 1550);
FORCEPROP 2 LAST CDS_LOCATION C2R9
J 2
(-5525 1450);
DISPLAY 0.617021 (-5525 1450);
PAINT AQUA (-5525 1450);
DISPLAY INVISIBLE (-5525 1450);
FORCEPROP 1 LAST PATH I147
J 2
(-5525 1500);
DISPLAY 0.978723 (-5525 1500);
PAINT WHITE (-5525 1500);
DISPLAY INVISIBLE (-5525 1500);
FORCEPROP 2 LAST ROOM PCIE_STEERING
J 2
(-5475 1350);
PAINT MONO (-5475 1350);
DISPLAY INVISIBLE (-5475 1350);
FORCEPROP 1 LASTPIN (-5475 1250) $PN 2
J 2
(-5485 1230);
DISPLAY 0.787234 (-5485 1230);
PAINT ORANGE (-5485 1230);
DISPLAY INVISIBLE (-5485 1230);
FORCEPROP 1 LASTPIN (-5475 1450) $PN 1
J 2
(-5485 1430);
DISPLAY 0.787234 (-5485 1430);
PAINT ORANGE (-5485 1430);
DISPLAY INVISIBLE (-5485 1430);
FORCEADD TAP..7
(-5475 1100);
FORCEPROP 3 LASTPIN (-5475 1150) SIG_NAME P3E_OCP_CPU0_PE3_C_TXN<7>
J 0
(-5465 1160);
DISPLAY 0.659574 (-5465 1160);
PAINT MONO (-5465 1160);
DISPLAY INVISIBLE (-5465 1160);
FORCEPROP 1 LASTPIN (-5475 1150) BN 7
R 1
J 0
(-5482 1098);
DISPLAY 0.617021 (-5482 1098);
PAINT GREEN (-5482 1098);
FORCEPROP 2 LAST CDS_LIB mstr_standard
J 0
(-5475 1100);
PAINT ORANGE (-5475 1100);
DISPLAY INVISIBLE (-5475 1100);
FORCEPROP 1 LAST BODY_TYPE PLUMBING
J 0
(-5425 1100);
DISPLAY 2.276596 (-5425 1100);
PAINT GREEN (-5425 1100);
DISPLAY INVISIBLE (-5425 1100);
FORCEPROP 1 LAST HDL_TAP TRUE
J 0
(-5155 970);
DISPLAY 2.276596 (-5155 970);
PAINT GREEN (-5155 970);
DISPLAY INVISIBLE (-5155 970);
FORCEPROP 1 LAST PATH I148
J 0
(-5477 1100);
DISPLAY 0.872340 (-5477 1100);
PAINT GREEN (-5477 1100);
DISPLAY INVISIBLE (-5477 1100);
FORCEADD OFFPAGE..2
(-3750 1050);
FORCEPROP 2 LAST $XR1 187 
J 0
(-3441 1050);
DISPLAY 0.638298 (-3441 1050);
PAINT MONO (-3441 1050);
FORCEPROP 2 LAST $XR0 186 
J 0
(-3561 1050);
DISPLAY 0.638298 (-3561 1050);
PAINT MONO (-3561 1050);
FORCEPROP 2 LAST CDS_LIB mstr_standard
J 0
(-3750 1050);
PAINT MONO (-3750 1050);
DISPLAY INVISIBLE (-3750 1050);
FORCEPROP 1 LAST OFFPAGE TRUE
J 0
(-3425 925);
DISPLAY 0.872340 (-3425 925);
PAINT GREEN (-3425 925);
DISPLAY INVISIBLE (-3425 925);
FORCEPROP 1 LAST COMMENT_BODY TRUE
J 0
(-3795 955);
DISPLAY 0.872340 (-3795 955);
PAINT GREEN (-3795 955);
DISPLAY INVISIBLE (-3795 955);
FORCEPROP 2 LAST PATH I151
J 0
(-3575 1125);
DISPLAY 1.021277 (-3575 1125);
PAINT ORANGE (-3575 1125);
DISPLAY INVISIBLE (-3575 1125);
FORCEADD OFFPAGE..2
(-3750 2050);
FORCEPROP 2 LAST $XR1 187 
J 0
(-3441 2050);
DISPLAY 0.638298 (-3441 2050);
PAINT MONO (-3441 2050);
FORCEPROP 2 LAST $XR0 186 
J 0
(-3561 2050);
DISPLAY 0.638298 (-3561 2050);
PAINT MONO (-3561 2050);
FORCEPROP 2 LAST CDS_LIB mstr_standard
J 0
(-3750 2050);
PAINT MONO (-3750 2050);
DISPLAY INVISIBLE (-3750 2050);
FORCEPROP 1 LAST OFFPAGE TRUE
J 0
(-3425 1925);
DISPLAY 0.872340 (-3425 1925);
PAINT GREEN (-3425 1925);
DISPLAY INVISIBLE (-3425 1925);
FORCEPROP 1 LAST COMMENT_BODY TRUE
J 0
(-3795 1955);
DISPLAY 0.872340 (-3795 1955);
PAINT GREEN (-3795 1955);
DISPLAY INVISIBLE (-3795 1955);
FORCEPROP 2 LAST PATH I152
J 0
(-3575 2125);
DISPLAY 1.021277 (-3575 2125);
PAINT ORANGE (-3575 2125);
DISPLAY INVISIBLE (-3575 2125);
FORCEADD TAP..7
(-4100 2100);
FORCEPROP 3 LASTPIN (-4100 2150) SIG_NAME P3E_OCP_CPU0_PE3_C_TXP<0>
J 0
(-4090 2160);
DISPLAY 0.659574 (-4090 2160);
PAINT MONO (-4090 2160);
DISPLAY INVISIBLE (-4090 2160);
FORCEPROP 1 LASTPIN (-4100 2150) BN 0
R 1
J 0
(-4107 2098);
DISPLAY 0.617021 (-4107 2098);
PAINT GREEN (-4107 2098);
FORCEPROP 2 LAST CDS_LIB mstr_standard
J 0
(-4100 2100);
PAINT ORANGE (-4100 2100);
DISPLAY INVISIBLE (-4100 2100);
FORCEPROP 1 LAST BODY_TYPE PLUMBING
J 0
(-4050 2100);
DISPLAY 2.276596 (-4050 2100);
PAINT GREEN (-4050 2100);
DISPLAY INVISIBLE (-4050 2100);
FORCEPROP 1 LAST HDL_TAP TRUE
J 0
(-3780 1970);
DISPLAY 2.276596 (-3780 1970);
PAINT GREEN (-3780 1970);
DISPLAY INVISIBLE (-3780 1970);
FORCEPROP 1 LAST PATH I25
J 0
(-4102 2100);
DISPLAY 0.872340 (-4102 2100);
PAINT GREEN (-4102 2100);
DISPLAY INVISIBLE (-4102 2100);
FORCEADD CAP..1
R 2
(-4300 2350);
FORCEPROP 1 LAST LOCATION C1R4
J 2
(-4350 2450);
DISPLAY 0.617021 (-4350 2450);
PAINT AQUA (-4350 2450);
FORCEPROP 1 LAST PART_NUMBER A36096-155
J 2
(-4350 2200);
DISPLAY 0.617021 (-4350 2200);
PAINT BLUE (-4350 2200);
FORCEPROP 1 LAST VALUE 0.22UF
J 2
(-4350 2400);
DISPLAY 0.617021 (-4350 2400);
PAINT SKYBLUE (-4350 2400);
FORCEPROP 1 LAST TOLERANCE 10%
J 2
(-4350 2300);
DISPLAY 0.617021 (-4350 2300);
PAINT SKYBLUE (-4350 2300);
FORCEPROP 1 LAST PACK_TYPE 0402
J 2
(-4350 2150);
DISPLAY 0.617021 (-4350 2150);
PAINT SKYBLUE (-4350 2150);
FORCEPROP 1 LAST VOLTAGE 16V
J 2
(-4350 2350);
DISPLAY 0.617021 (-4350 2350);
PAINT SKYBLUE (-4350 2350);
FORCEPROP 1 LAST MATERIAL X7R
J 2
(-4350 2250);
DISPLAY 0.617021 (-4350 2250);
PAINT SKYBLUE (-4350 2250);
FORCEPROP 2 LAST BOM_COST IO_SLOT
J 0
(-4550 2500);
PAINT MONO (-4550 2500);
DISPLAY INVISIBLE (-4550 2500);
FORCEPROP 2 LAST CDS_LIB mstr_discrete
J 0
(-4300 2350);
PAINT ORANGE (-4300 2350);
DISPLAY INVISIBLE (-4300 2350);
FORCEPROP 0 LAST CDS_SEC 1
J 0
(-4350 2500);
PAINT ORANGE (-4350 2500);
DISPLAY INVISIBLE (-4350 2500);
FORCEPROP 2 LAST $SEC 1
J 0
(-4350 2550);
DISPLAY 0.680851 (-4350 2550);
PAINT MONO (-4350 2550);
DISPLAY INVISIBLE (-4350 2550);
FORCEPROP 2 LAST CDS_LOCATION C1R4
J 2
(-4350 2450);
DISPLAY 0.617021 (-4350 2450);
PAINT AQUA (-4350 2450);
DISPLAY INVISIBLE (-4350 2450);
FORCEPROP 1 LAST PATH I26
J 2
(-4350 2500);
DISPLAY 0.978723 (-4350 2500);
PAINT WHITE (-4350 2500);
DISPLAY INVISIBLE (-4350 2500);
FORCEPROP 2 LAST ROOM PCIE_STEERING
J 2
(-4300 2350);
PAINT MONO (-4300 2350);
DISPLAY INVISIBLE (-4300 2350);
FORCEPROP 1 LASTPIN (-4300 2250) $PN 2
J 2
(-4310 2230);
DISPLAY 0.787234 (-4310 2230);
PAINT ORANGE (-4310 2230);
DISPLAY INVISIBLE (-4310 2230);
FORCEPROP 1 LASTPIN (-4300 2450) $PN 1
J 2
(-4310 2430);
DISPLAY 0.787234 (-4310 2430);
PAINT ORANGE (-4310 2430);
DISPLAY INVISIBLE (-4310 2430);
FORCEADD TAP..7
(-4300 2100);
FORCEPROP 3 LASTPIN (-4300 2150) SIG_NAME P3E_OCP_CPU0_PE3_C_TXP<1>
J 0
(-4290 2160);
DISPLAY 0.659574 (-4290 2160);
PAINT MONO (-4290 2160);
DISPLAY INVISIBLE (-4290 2160);
FORCEPROP 1 LASTPIN (-4300 2150) BN 1
R 1
J 0
(-4307 2098);
DISPLAY 0.617021 (-4307 2098);
PAINT GREEN (-4307 2098);
FORCEPROP 2 LAST CDS_LIB mstr_standard
J 0
(-4300 2100);
PAINT ORANGE (-4300 2100);
DISPLAY INVISIBLE (-4300 2100);
FORCEPROP 1 LAST BODY_TYPE PLUMBING
J 0
(-4250 2100);
DISPLAY 2.276596 (-4250 2100);
PAINT GREEN (-4250 2100);
DISPLAY INVISIBLE (-4250 2100);
FORCEPROP 1 LAST HDL_TAP TRUE
J 0
(-3980 1970);
DISPLAY 2.276596 (-3980 1970);
PAINT GREEN (-3980 1970);
DISPLAY INVISIBLE (-3980 1970);
FORCEPROP 1 LAST PATH I27
J 0
(-4302 2100);
DISPLAY 0.872340 (-4302 2100);
PAINT GREEN (-4302 2100);
DISPLAY INVISIBLE (-4302 2100);
FORCEADD TAP..3
(-4075 1900);
FORCEPROP 3 LASTPIN (-4075 1850) SIG_NAME P3E_CPU0_PE3_OCP_TXN<0>
J 0
(-4065 1860);
DISPLAY 0.659574 (-4065 1860);
PAINT MONO (-4065 1860);
DISPLAY INVISIBLE (-4065 1860);
FORCEPROP 1 LASTPIN (-4075 1850) BN 0
R 1
J 0
(-4082 1838);
DISPLAY 0.617021 (-4082 1838);
PAINT GREEN (-4082 1838);
FORCEPROP 2 LAST CDS_LIB mstr_standard
J 0
(-4075 1900);
PAINT ORANGE (-4075 1900);
DISPLAY INVISIBLE (-4075 1900);
FORCEPROP 1 LAST BODY_TYPE PLUMBING
J 0
(-4025 1850);
DISPLAY 2.276596 (-4025 1850);
PAINT GREEN (-4025 1850);
DISPLAY INVISIBLE (-4025 1850);
FORCEPROP 1 LAST HDL_TAP TRUE
J 0
(-3755 1770);
DISPLAY 2.276596 (-3755 1770);
PAINT GREEN (-3755 1770);
DISPLAY INVISIBLE (-3755 1770);
FORCEPROP 1 LAST PATH I28
J 0
(-4077 1900);
DISPLAY 0.872340 (-4077 1900);
PAINT GREEN (-4077 1900);
DISPLAY INVISIBLE (-4077 1900);
FORCEADD CAP..1
R 2
(-4075 1650);
FORCEPROP 1 LAST LOCATION C1R1
J 2
(-4125 1750);
DISPLAY 0.617021 (-4125 1750);
PAINT AQUA (-4125 1750);
FORCEPROP 1 LAST PART_NUMBER A36096-155
J 2
(-4125 1500);
DISPLAY 0.617021 (-4125 1500);
PAINT BLUE (-4125 1500);
FORCEPROP 1 LAST VALUE 0.22UF
J 2
(-4125 1700);
DISPLAY 0.617021 (-4125 1700);
PAINT SKYBLUE (-4125 1700);
FORCEPROP 1 LAST TOLERANCE 10%
J 2
(-4125 1600);
DISPLAY 0.617021 (-4125 1600);
PAINT SKYBLUE (-4125 1600);
FORCEPROP 1 LAST PACK_TYPE 0402
J 2
(-4125 1450);
DISPLAY 0.617021 (-4125 1450);
PAINT SKYBLUE (-4125 1450);
FORCEPROP 1 LAST VOLTAGE 16V
J 2
(-4125 1650);
DISPLAY 0.617021 (-4125 1650);
PAINT SKYBLUE (-4125 1650);
FORCEPROP 1 LAST MATERIAL X7R
J 2
(-4125 1550);
DISPLAY 0.617021 (-4125 1550);
PAINT SKYBLUE (-4125 1550);
FORCEPROP 2 LAST BOM_COST IO_SLOT
J 0
(-4325 1800);
PAINT MONO (-4325 1800);
DISPLAY INVISIBLE (-4325 1800);
FORCEPROP 2 LAST CDS_LIB mstr_discrete
J 0
(-4075 1650);
PAINT ORANGE (-4075 1650);
DISPLAY INVISIBLE (-4075 1650);
FORCEPROP 0 LAST CDS_SEC 1
J 0
(-4125 1800);
PAINT ORANGE (-4125 1800);
DISPLAY INVISIBLE (-4125 1800);
FORCEPROP 2 LAST $SEC 1
J 0
(-4125 1850);
DISPLAY 0.680851 (-4125 1850);
PAINT MONO (-4125 1850);
DISPLAY INVISIBLE (-4125 1850);
FORCEPROP 2 LAST CDS_LOCATION C1R1
J 2
(-4125 1750);
DISPLAY 0.617021 (-4125 1750);
PAINT AQUA (-4125 1750);
DISPLAY INVISIBLE (-4125 1750);
FORCEPROP 1 LAST PATH I29
J 2
(-4125 1800);
DISPLAY 0.978723 (-4125 1800);
PAINT WHITE (-4125 1800);
DISPLAY INVISIBLE (-4125 1800);
FORCEPROP 2 LAST ROOM PCIE_STEERING
J 2
(-4075 1650);
PAINT MONO (-4075 1650);
DISPLAY INVISIBLE (-4075 1650);
FORCEPROP 1 LASTPIN (-4075 1550) $PN 2
J 2
(-4085 1530);
DISPLAY 0.787234 (-4085 1530);
PAINT ORANGE (-4085 1530);
DISPLAY INVISIBLE (-4085 1530);
FORCEPROP 1 LASTPIN (-4075 1750) $PN 1
J 2
(-4085 1730);
DISPLAY 0.787234 (-4085 1730);
PAINT ORANGE (-4085 1730);
DISPLAY INVISIBLE (-4085 1730);
FORCEADD TAP..3
(-4275 1900);
FORCEPROP 3 LASTPIN (-4275 1850) SIG_NAME P3E_CPU0_PE3_OCP_TXN<1>
J 0
(-4265 1860);
DISPLAY 0.659574 (-4265 1860);
PAINT MONO (-4265 1860);
DISPLAY INVISIBLE (-4265 1860);
FORCEPROP 1 LASTPIN (-4275 1850) BN 1
R 1
J 0
(-4282 1838);
DISPLAY 0.617021 (-4282 1838);
PAINT GREEN (-4282 1838);
FORCEPROP 2 LAST CDS_LIB mstr_standard
J 0
(-4275 1900);
PAINT ORANGE (-4275 1900);
DISPLAY INVISIBLE (-4275 1900);
FORCEPROP 1 LAST BODY_TYPE PLUMBING
J 0
(-4225 1850);
DISPLAY 2.276596 (-4225 1850);
PAINT GREEN (-4225 1850);
DISPLAY INVISIBLE (-4225 1850);
FORCEPROP 1 LAST HDL_TAP TRUE
J 0
(-3955 1770);
DISPLAY 2.276596 (-3955 1770);
PAINT GREEN (-3955 1770);
DISPLAY INVISIBLE (-3955 1770);
FORCEPROP 1 LAST PATH I30
J 0
(-4277 1900);
DISPLAY 0.872340 (-4277 1900);
PAINT GREEN (-4277 1900);
DISPLAY INVISIBLE (-4277 1900);
FORCEADD TAP..7
(-4075 1100);
FORCEPROP 3 LASTPIN (-4075 1150) SIG_NAME P3E_OCP_CPU0_PE3_C_TXN<0>
J 0
(-4065 1160);
DISPLAY 0.659574 (-4065 1160);
PAINT MONO (-4065 1160);
DISPLAY INVISIBLE (-4065 1160);
FORCEPROP 1 LASTPIN (-4075 1150) BN 0
R 1
J 0
(-4082 1098);
DISPLAY 0.617021 (-4082 1098);
PAINT GREEN (-4082 1098);
FORCEPROP 2 LAST CDS_LIB mstr_standard
J 0
(-4075 1100);
PAINT ORANGE (-4075 1100);
DISPLAY INVISIBLE (-4075 1100);
FORCEPROP 1 LAST BODY_TYPE PLUMBING
J 0
(-4025 1100);
DISPLAY 2.276596 (-4025 1100);
PAINT GREEN (-4025 1100);
DISPLAY INVISIBLE (-4025 1100);
FORCEPROP 1 LAST HDL_TAP TRUE
J 0
(-3755 970);
DISPLAY 2.276596 (-3755 970);
PAINT GREEN (-3755 970);
DISPLAY INVISIBLE (-3755 970);
FORCEPROP 1 LAST PATH I36
J 0
(-4077 1100);
DISPLAY 0.872340 (-4077 1100);
PAINT GREEN (-4077 1100);
DISPLAY INVISIBLE (-4077 1100);
FORCEADD CAP..1
R 2
(-4275 1350);
FORCEPROP 1 LAST LOCATION C1R3
J 2
(-4325 1450);
DISPLAY 0.617021 (-4325 1450);
PAINT AQUA (-4325 1450);
FORCEPROP 1 LAST PART_NUMBER A36096-155
J 2
(-4325 1200);
DISPLAY 0.617021 (-4325 1200);
PAINT BLUE (-4325 1200);
FORCEPROP 1 LAST VALUE 0.22UF
J 2
(-4325 1400);
DISPLAY 0.617021 (-4325 1400);
PAINT SKYBLUE (-4325 1400);
FORCEPROP 1 LAST TOLERANCE 10%
J 2
(-4325 1300);
DISPLAY 0.617021 (-4325 1300);
PAINT SKYBLUE (-4325 1300);
FORCEPROP 1 LAST PACK_TYPE 0402
J 2
(-4325 1150);
DISPLAY 0.617021 (-4325 1150);
PAINT SKYBLUE (-4325 1150);
FORCEPROP 1 LAST VOLTAGE 16V
J 2
(-4325 1350);
DISPLAY 0.617021 (-4325 1350);
PAINT SKYBLUE (-4325 1350);
FORCEPROP 1 LAST MATERIAL X7R
J 2
(-4325 1250);
DISPLAY 0.617021 (-4325 1250);
PAINT SKYBLUE (-4325 1250);
FORCEPROP 2 LAST BOM_COST IO_SLOT
J 0
(-4525 1500);
PAINT MONO (-4525 1500);
DISPLAY INVISIBLE (-4525 1500);
FORCEPROP 2 LAST CDS_LIB mstr_discrete
J 0
(-4275 1350);
PAINT ORANGE (-4275 1350);
DISPLAY INVISIBLE (-4275 1350);
FORCEPROP 0 LAST CDS_SEC 1
J 0
(-4325 1500);
PAINT ORANGE (-4325 1500);
DISPLAY INVISIBLE (-4325 1500);
FORCEPROP 2 LAST $SEC 1
J 0
(-4325 1550);
DISPLAY 0.680851 (-4325 1550);
PAINT MONO (-4325 1550);
DISPLAY INVISIBLE (-4325 1550);
FORCEPROP 2 LAST CDS_LOCATION C1R3
J 2
(-4325 1450);
DISPLAY 0.617021 (-4325 1450);
PAINT AQUA (-4325 1450);
DISPLAY INVISIBLE (-4325 1450);
FORCEPROP 1 LAST PATH I37
J 2
(-4325 1500);
DISPLAY 0.978723 (-4325 1500);
PAINT WHITE (-4325 1500);
DISPLAY INVISIBLE (-4325 1500);
FORCEPROP 2 LAST ROOM PCIE_STEERING
J 2
(-4275 1350);
PAINT MONO (-4275 1350);
DISPLAY INVISIBLE (-4275 1350);
FORCEPROP 1 LASTPIN (-4275 1250) $PN 2
J 2
(-4285 1230);
DISPLAY 0.787234 (-4285 1230);
PAINT ORANGE (-4285 1230);
DISPLAY INVISIBLE (-4285 1230);
FORCEPROP 1 LASTPIN (-4275 1450) $PN 1
J 2
(-4285 1430);
DISPLAY 0.787234 (-4285 1430);
PAINT ORANGE (-4285 1430);
DISPLAY INVISIBLE (-4285 1430);
FORCEADD TAP..7
(-4275 1100);
FORCEPROP 3 LASTPIN (-4275 1150) SIG_NAME P3E_OCP_CPU0_PE3_C_TXN<1>
J 0
(-4265 1160);
DISPLAY 0.659574 (-4265 1160);
PAINT MONO (-4265 1160);
DISPLAY INVISIBLE (-4265 1160);
FORCEPROP 1 LASTPIN (-4275 1150) BN 1
R 1
J 0
(-4282 1098);
DISPLAY 0.617021 (-4282 1098);
PAINT GREEN (-4282 1098);
FORCEPROP 2 LAST CDS_LIB mstr_standard
J 0
(-4275 1100);
PAINT ORANGE (-4275 1100);
DISPLAY INVISIBLE (-4275 1100);
FORCEPROP 1 LAST BODY_TYPE PLUMBING
J 0
(-4225 1100);
DISPLAY 2.276596 (-4225 1100);
PAINT GREEN (-4225 1100);
DISPLAY INVISIBLE (-4225 1100);
FORCEPROP 1 LAST HDL_TAP TRUE
J 0
(-3955 970);
DISPLAY 2.276596 (-3955 970);
PAINT GREEN (-3955 970);
DISPLAY INVISIBLE (-3955 970);
FORCEPROP 1 LAST PATH I38
J 0
(-4277 1100);
DISPLAY 0.872340 (-4277 1100);
PAINT GREEN (-4277 1100);
DISPLAY INVISIBLE (-4277 1100);
FORCEADD TAP..3
(-4500 2900);
FORCEPROP 3 LASTPIN (-4500 2850) SIG_NAME P3E_CPU0_PE3_OCP_TXP<2>
J 0
(-4490 2860);
DISPLAY 0.659574 (-4490 2860);
PAINT MONO (-4490 2860);
DISPLAY INVISIBLE (-4490 2860);
FORCEPROP 1 LASTPIN (-4500 2850) BN 2
R 1
J 0
(-4507 2838);
DISPLAY 0.617021 (-4507 2838);
PAINT GREEN (-4507 2838);
FORCEPROP 2 LAST CDS_LIB mstr_standard
J 0
(-4500 2900);
PAINT ORANGE (-4500 2900);
DISPLAY INVISIBLE (-4500 2900);
FORCEPROP 1 LAST BODY_TYPE PLUMBING
J 0
(-4450 2850);
DISPLAY 2.276596 (-4450 2850);
PAINT GREEN (-4450 2850);
DISPLAY INVISIBLE (-4450 2850);
FORCEPROP 1 LAST HDL_TAP TRUE
J 0
(-4180 2770);
DISPLAY 2.276596 (-4180 2770);
PAINT GREEN (-4180 2770);
DISPLAY INVISIBLE (-4180 2770);
FORCEPROP 1 LAST PATH I39
J 0
(-4502 2900);
DISPLAY 0.872340 (-4502 2900);
PAINT GREEN (-4502 2900);
DISPLAY INVISIBLE (-4502 2900);
FORCEADD CAP..1
R 2
(-4500 2650);
FORCEPROP 1 LAST LOCATION C1R6
J 2
(-4550 2750);
DISPLAY 0.617021 (-4550 2750);
PAINT AQUA (-4550 2750);
FORCEPROP 1 LAST PART_NUMBER A36096-155
J 2
(-4550 2500);
DISPLAY 0.617021 (-4550 2500);
PAINT BLUE (-4550 2500);
FORCEPROP 1 LAST VALUE 0.22UF
J 2
(-4550 2700);
DISPLAY 0.617021 (-4550 2700);
PAINT SKYBLUE (-4550 2700);
FORCEPROP 1 LAST TOLERANCE 10%
J 2
(-4550 2600);
DISPLAY 0.617021 (-4550 2600);
PAINT SKYBLUE (-4550 2600);
FORCEPROP 1 LAST PACK_TYPE 0402
J 2
(-4550 2450);
DISPLAY 0.617021 (-4550 2450);
PAINT SKYBLUE (-4550 2450);
FORCEPROP 1 LAST VOLTAGE 16V
J 2
(-4550 2650);
DISPLAY 0.617021 (-4550 2650);
PAINT SKYBLUE (-4550 2650);
FORCEPROP 1 LAST MATERIAL X7R
J 2
(-4550 2550);
DISPLAY 0.617021 (-4550 2550);
PAINT SKYBLUE (-4550 2550);
FORCEPROP 2 LAST CDS_LIB mstr_discrete
J 0
(-4500 2650);
PAINT ORANGE (-4500 2650);
DISPLAY INVISIBLE (-4500 2650);
FORCEPROP 0 LAST CDS_SEC 1
J 0
(-4550 2800);
PAINT ORANGE (-4550 2800);
DISPLAY INVISIBLE (-4550 2800);
FORCEPROP 2 LAST $SEC 1
J 0
(-4550 2850);
DISPLAY 0.680851 (-4550 2850);
PAINT MONO (-4550 2850);
DISPLAY INVISIBLE (-4550 2850);
FORCEPROP 2 LAST CDS_LOCATION C1R6
J 2
(-4550 2750);
DISPLAY 0.617021 (-4550 2750);
PAINT AQUA (-4550 2750);
DISPLAY INVISIBLE (-4550 2750);
FORCEPROP 1 LAST PATH I40
J 2
(-4550 2800);
DISPLAY 0.978723 (-4550 2800);
PAINT WHITE (-4550 2800);
DISPLAY INVISIBLE (-4550 2800);
FORCEPROP 2 LAST ROOM PCIE_STEERING
J 2
(-4500 2650);
PAINT MONO (-4500 2650);
DISPLAY INVISIBLE (-4500 2650);
FORCEPROP 1 LASTPIN (-4500 2550) $PN 2
J 2
(-4510 2530);
DISPLAY 0.787234 (-4510 2530);
PAINT ORANGE (-4510 2530);
DISPLAY INVISIBLE (-4510 2530);
FORCEPROP 1 LASTPIN (-4500 2750) $PN 1
J 2
(-4510 2730);
DISPLAY 0.787234 (-4510 2730);
PAINT ORANGE (-4510 2730);
DISPLAY INVISIBLE (-4510 2730);
FORCEADD TAP..3
(-4700 2900);
FORCEPROP 3 LASTPIN (-4700 2850) SIG_NAME P3E_CPU0_PE3_OCP_TXP<3>
J 0
(-4690 2860);
DISPLAY 0.659574 (-4690 2860);
PAINT MONO (-4690 2860);
DISPLAY INVISIBLE (-4690 2860);
FORCEPROP 1 LASTPIN (-4700 2850) BN 3
R 1
J 0
(-4707 2838);
DISPLAY 0.617021 (-4707 2838);
PAINT GREEN (-4707 2838);
FORCEPROP 2 LAST CDS_LIB mstr_standard
J 0
(-4700 2900);
PAINT ORANGE (-4700 2900);
DISPLAY INVISIBLE (-4700 2900);
FORCEPROP 1 LAST BODY_TYPE PLUMBING
J 0
(-4650 2850);
DISPLAY 2.276596 (-4650 2850);
PAINT GREEN (-4650 2850);
DISPLAY INVISIBLE (-4650 2850);
FORCEPROP 1 LAST HDL_TAP TRUE
J 0
(-4380 2770);
DISPLAY 2.276596 (-4380 2770);
PAINT GREEN (-4380 2770);
DISPLAY INVISIBLE (-4380 2770);
FORCEPROP 1 LAST PATH I41
J 0
(-4702 2900);
DISPLAY 0.872340 (-4702 2900);
PAINT GREEN (-4702 2900);
DISPLAY INVISIBLE (-4702 2900);
FORCEADD TAP..7
(-4500 2100);
FORCEPROP 3 LASTPIN (-4500 2150) SIG_NAME P3E_OCP_CPU0_PE3_C_TXP<2>
J 0
(-4490 2160);
DISPLAY 0.659574 (-4490 2160);
PAINT MONO (-4490 2160);
DISPLAY INVISIBLE (-4490 2160);
FORCEPROP 1 LASTPIN (-4500 2150) BN 2
R 1
J 0
(-4507 2098);
DISPLAY 0.617021 (-4507 2098);
PAINT GREEN (-4507 2098);
FORCEPROP 2 LAST CDS_LIB mstr_standard
J 0
(-4500 2100);
PAINT ORANGE (-4500 2100);
DISPLAY INVISIBLE (-4500 2100);
FORCEPROP 1 LAST BODY_TYPE PLUMBING
J 0
(-4450 2100);
DISPLAY 2.276596 (-4450 2100);
PAINT GREEN (-4450 2100);
DISPLAY INVISIBLE (-4450 2100);
FORCEPROP 1 LAST HDL_TAP TRUE
J 0
(-4180 1970);
DISPLAY 2.276596 (-4180 1970);
PAINT GREEN (-4180 1970);
DISPLAY INVISIBLE (-4180 1970);
FORCEPROP 1 LAST PATH I54
J 0
(-4502 2100);
DISPLAY 0.872340 (-4502 2100);
PAINT GREEN (-4502 2100);
DISPLAY INVISIBLE (-4502 2100);
FORCEADD CAP..1
R 2
(-4700 2350);
FORCEPROP 1 LAST LOCATION C1R8
J 2
(-4750 2450);
DISPLAY 0.617021 (-4750 2450);
PAINT AQUA (-4750 2450);
FORCEPROP 1 LAST PART_NUMBER A36096-155
J 2
(-4750 2200);
DISPLAY 0.617021 (-4750 2200);
PAINT BLUE (-4750 2200);
FORCEPROP 1 LAST VALUE 0.22UF
J 2
(-4750 2400);
DISPLAY 0.617021 (-4750 2400);
PAINT SKYBLUE (-4750 2400);
FORCEPROP 1 LAST TOLERANCE 10%
J 2
(-4750 2300);
DISPLAY 0.617021 (-4750 2300);
PAINT SKYBLUE (-4750 2300);
FORCEPROP 1 LAST PACK_TYPE 0402
J 2
(-4750 2150);
DISPLAY 0.617021 (-4750 2150);
PAINT SKYBLUE (-4750 2150);
FORCEPROP 1 LAST VOLTAGE 16V
J 2
(-4750 2350);
DISPLAY 0.617021 (-4750 2350);
PAINT SKYBLUE (-4750 2350);
FORCEPROP 1 LAST MATERIAL X7R
J 2
(-4750 2250);
DISPLAY 0.617021 (-4750 2250);
PAINT SKYBLUE (-4750 2250);
FORCEPROP 2 LAST CDS_LIB mstr_discrete
J 0
(-4700 2350);
PAINT ORANGE (-4700 2350);
DISPLAY INVISIBLE (-4700 2350);
FORCEPROP 0 LAST CDS_SEC 1
J 0
(-4750 2500);
PAINT ORANGE (-4750 2500);
DISPLAY INVISIBLE (-4750 2500);
FORCEPROP 2 LAST $SEC 1
J 0
(-4750 2550);
DISPLAY 0.680851 (-4750 2550);
PAINT MONO (-4750 2550);
DISPLAY INVISIBLE (-4750 2550);
FORCEPROP 2 LAST CDS_LOCATION C1R8
J 2
(-4750 2450);
DISPLAY 0.617021 (-4750 2450);
PAINT AQUA (-4750 2450);
DISPLAY INVISIBLE (-4750 2450);
FORCEPROP 1 LAST PATH I55
J 2
(-4750 2500);
DISPLAY 0.978723 (-4750 2500);
PAINT WHITE (-4750 2500);
DISPLAY INVISIBLE (-4750 2500);
FORCEPROP 2 LAST ROOM PCIE_STEERING
J 2
(-4700 2350);
PAINT MONO (-4700 2350);
DISPLAY INVISIBLE (-4700 2350);
FORCEPROP 1 LASTPIN (-4700 2250) $PN 2
J 2
(-4710 2230);
DISPLAY 0.787234 (-4710 2230);
PAINT ORANGE (-4710 2230);
DISPLAY INVISIBLE (-4710 2230);
FORCEPROP 1 LASTPIN (-4700 2450) $PN 1
J 2
(-4710 2430);
DISPLAY 0.787234 (-4710 2430);
PAINT ORANGE (-4710 2430);
DISPLAY INVISIBLE (-4710 2430);
FORCEADD TAP..7
(-4700 2100);
FORCEPROP 3 LASTPIN (-4700 2150) SIG_NAME P3E_OCP_CPU0_PE3_C_TXP<3>
J 0
(-4690 2160);
DISPLAY 0.659574 (-4690 2160);
PAINT MONO (-4690 2160);
DISPLAY INVISIBLE (-4690 2160);
FORCEPROP 1 LASTPIN (-4700 2150) BN 3
R 1
J 0
(-4707 2098);
DISPLAY 0.617021 (-4707 2098);
PAINT GREEN (-4707 2098);
FORCEPROP 2 LAST CDS_LIB mstr_standard
J 0
(-4700 2100);
PAINT ORANGE (-4700 2100);
DISPLAY INVISIBLE (-4700 2100);
FORCEPROP 1 LAST BODY_TYPE PLUMBING
J 0
(-4650 2100);
DISPLAY 2.276596 (-4650 2100);
PAINT GREEN (-4650 2100);
DISPLAY INVISIBLE (-4650 2100);
FORCEPROP 1 LAST HDL_TAP TRUE
J 0
(-4380 1970);
DISPLAY 2.276596 (-4380 1970);
PAINT GREEN (-4380 1970);
DISPLAY INVISIBLE (-4380 1970);
FORCEPROP 1 LAST PATH I56
J 0
(-4702 2100);
DISPLAY 0.872340 (-4702 2100);
PAINT GREEN (-4702 2100);
DISPLAY INVISIBLE (-4702 2100);
FORCEADD TAP..3
(-4475 1900);
FORCEPROP 3 LASTPIN (-4475 1850) SIG_NAME P3E_CPU0_PE3_OCP_TXN<2>
J 0
(-4465 1860);
DISPLAY 0.659574 (-4465 1860);
PAINT MONO (-4465 1860);
DISPLAY INVISIBLE (-4465 1860);
FORCEPROP 1 LASTPIN (-4475 1850) BN 2
R 1
J 0
(-4482 1838);
DISPLAY 0.617021 (-4482 1838);
PAINT GREEN (-4482 1838);
FORCEPROP 2 LAST CDS_LIB mstr_standard
J 0
(-4475 1900);
PAINT ORANGE (-4475 1900);
DISPLAY INVISIBLE (-4475 1900);
FORCEPROP 1 LAST BODY_TYPE PLUMBING
J 0
(-4425 1850);
DISPLAY 2.276596 (-4425 1850);
PAINT GREEN (-4425 1850);
DISPLAY INVISIBLE (-4425 1850);
FORCEPROP 1 LAST HDL_TAP TRUE
J 0
(-4155 1770);
DISPLAY 2.276596 (-4155 1770);
PAINT GREEN (-4155 1770);
DISPLAY INVISIBLE (-4155 1770);
FORCEPROP 1 LAST PATH I58
J 0
(-4477 1900);
DISPLAY 0.872340 (-4477 1900);
PAINT GREEN (-4477 1900);
DISPLAY INVISIBLE (-4477 1900);
FORCEADD CAP..1
R 2
(-4475 1650);
FORCEPROP 1 LAST LOCATION C1R5
J 2
(-4525 1750);
DISPLAY 0.617021 (-4525 1750);
PAINT AQUA (-4525 1750);
FORCEPROP 1 LAST PART_NUMBER A36096-155
J 2
(-4525 1500);
DISPLAY 0.617021 (-4525 1500);
PAINT BLUE (-4525 1500);
FORCEPROP 1 LAST VALUE 0.22UF
J 2
(-4525 1700);
DISPLAY 0.617021 (-4525 1700);
PAINT SKYBLUE (-4525 1700);
FORCEPROP 1 LAST TOLERANCE 10%
J 2
(-4525 1600);
DISPLAY 0.617021 (-4525 1600);
PAINT SKYBLUE (-4525 1600);
FORCEPROP 1 LAST PACK_TYPE 0402
J 2
(-4525 1450);
DISPLAY 0.617021 (-4525 1450);
PAINT SKYBLUE (-4525 1450);
FORCEPROP 1 LAST VOLTAGE 16V
J 2
(-4525 1650);
DISPLAY 0.617021 (-4525 1650);
PAINT SKYBLUE (-4525 1650);
FORCEPROP 1 LAST MATERIAL X7R
J 2
(-4525 1550);
DISPLAY 0.617021 (-4525 1550);
PAINT SKYBLUE (-4525 1550);
FORCEPROP 2 LAST BOM_COST IO_SLOT
J 0
(-4725 1800);
PAINT MONO (-4725 1800);
DISPLAY INVISIBLE (-4725 1800);
FORCEPROP 2 LAST CDS_LIB mstr_discrete
J 0
(-4475 1650);
PAINT ORANGE (-4475 1650);
DISPLAY INVISIBLE (-4475 1650);
FORCEPROP 0 LAST CDS_SEC 1
J 0
(-4525 1800);
PAINT ORANGE (-4525 1800);
DISPLAY INVISIBLE (-4525 1800);
FORCEPROP 2 LAST $SEC 1
J 0
(-4525 1850);
DISPLAY 0.680851 (-4525 1850);
PAINT MONO (-4525 1850);
DISPLAY INVISIBLE (-4525 1850);
FORCEPROP 2 LAST CDS_LOCATION C1R5
J 2
(-4525 1750);
DISPLAY 0.617021 (-4525 1750);
PAINT AQUA (-4525 1750);
DISPLAY INVISIBLE (-4525 1750);
FORCEPROP 1 LAST PATH I59
J 2
(-4525 1800);
DISPLAY 0.978723 (-4525 1800);
PAINT WHITE (-4525 1800);
DISPLAY INVISIBLE (-4525 1800);
FORCEPROP 2 LAST ROOM PCIE_STEERING
J 2
(-4475 1650);
PAINT MONO (-4475 1650);
DISPLAY INVISIBLE (-4475 1650);
FORCEPROP 1 LASTPIN (-4475 1550) $PN 2
J 2
(-4485 1530);
DISPLAY 0.787234 (-4485 1530);
PAINT ORANGE (-4485 1530);
DISPLAY INVISIBLE (-4485 1530);
FORCEPROP 1 LASTPIN (-4475 1750) $PN 1
J 2
(-4485 1730);
DISPLAY 0.787234 (-4485 1730);
PAINT ORANGE (-4485 1730);
DISPLAY INVISIBLE (-4485 1730);
FORCEADD TAP..3
(-4675 1900);
FORCEPROP 3 LASTPIN (-4675 1850) SIG_NAME P3E_CPU0_PE3_OCP_TXN<3>
J 0
(-4665 1860);
DISPLAY 0.659574 (-4665 1860);
PAINT MONO (-4665 1860);
DISPLAY INVISIBLE (-4665 1860);
FORCEPROP 1 LASTPIN (-4675 1850) BN 3
R 1
J 0
(-4682 1838);
DISPLAY 0.617021 (-4682 1838);
PAINT GREEN (-4682 1838);
FORCEPROP 2 LAST CDS_LIB mstr_standard
J 0
(-4675 1900);
PAINT ORANGE (-4675 1900);
DISPLAY INVISIBLE (-4675 1900);
FORCEPROP 1 LAST BODY_TYPE PLUMBING
J 0
(-4625 1850);
DISPLAY 2.276596 (-4625 1850);
PAINT GREEN (-4625 1850);
DISPLAY INVISIBLE (-4625 1850);
FORCEPROP 1 LAST HDL_TAP TRUE
J 0
(-4355 1770);
DISPLAY 2.276596 (-4355 1770);
PAINT GREEN (-4355 1770);
DISPLAY INVISIBLE (-4355 1770);
FORCEPROP 1 LAST PATH I60
J 0
(-4677 1900);
DISPLAY 0.872340 (-4677 1900);
PAINT GREEN (-4677 1900);
DISPLAY INVISIBLE (-4677 1900);
FORCEADD TAP..7
(-4475 1100);
FORCEPROP 3 LASTPIN (-4475 1150) SIG_NAME P3E_OCP_CPU0_PE3_C_TXN<2>
J 0
(-4465 1160);
DISPLAY 0.659574 (-4465 1160);
PAINT MONO (-4465 1160);
DISPLAY INVISIBLE (-4465 1160);
FORCEPROP 1 LASTPIN (-4475 1150) BN 2
R 1
J 0
(-4482 1098);
DISPLAY 0.617021 (-4482 1098);
PAINT GREEN (-4482 1098);
FORCEPROP 2 LAST CDS_LIB mstr_standard
J 0
(-4475 1100);
PAINT ORANGE (-4475 1100);
DISPLAY INVISIBLE (-4475 1100);
FORCEPROP 1 LAST BODY_TYPE PLUMBING
J 0
(-4425 1100);
DISPLAY 2.276596 (-4425 1100);
PAINT GREEN (-4425 1100);
DISPLAY INVISIBLE (-4425 1100);
FORCEPROP 1 LAST HDL_TAP TRUE
J 0
(-4155 970);
DISPLAY 2.276596 (-4155 970);
PAINT GREEN (-4155 970);
DISPLAY INVISIBLE (-4155 970);
FORCEPROP 1 LAST PATH I69
J 0
(-4477 1100);
DISPLAY 0.872340 (-4477 1100);
PAINT GREEN (-4477 1100);
DISPLAY INVISIBLE (-4477 1100);
FORCEADD CAP..1
R 2
(-4675 1350);
FORCEPROP 1 LAST LOCATION C1R7
J 2
(-4725 1450);
DISPLAY 0.617021 (-4725 1450);
PAINT AQUA (-4725 1450);
FORCEPROP 1 LAST PART_NUMBER A36096-155
J 2
(-4725 1200);
DISPLAY 0.617021 (-4725 1200);
PAINT BLUE (-4725 1200);
FORCEPROP 1 LAST VALUE 0.22UF
J 2
(-4725 1400);
DISPLAY 0.617021 (-4725 1400);
PAINT SKYBLUE (-4725 1400);
FORCEPROP 1 LAST TOLERANCE 10%
J 2
(-4725 1300);
DISPLAY 0.617021 (-4725 1300);
PAINT SKYBLUE (-4725 1300);
FORCEPROP 1 LAST PACK_TYPE 0402
J 2
(-4725 1150);
DISPLAY 0.617021 (-4725 1150);
PAINT SKYBLUE (-4725 1150);
FORCEPROP 1 LAST VOLTAGE 16V
J 2
(-4725 1350);
DISPLAY 0.617021 (-4725 1350);
PAINT SKYBLUE (-4725 1350);
FORCEPROP 1 LAST MATERIAL X7R
J 2
(-4725 1250);
DISPLAY 0.617021 (-4725 1250);
PAINT SKYBLUE (-4725 1250);
FORCEPROP 2 LAST BOM_COST IO_SLOT
J 0
(-4925 1500);
PAINT MONO (-4925 1500);
DISPLAY INVISIBLE (-4925 1500);
FORCEPROP 2 LAST CDS_LIB mstr_discrete
J 0
(-4675 1350);
PAINT ORANGE (-4675 1350);
DISPLAY INVISIBLE (-4675 1350);
FORCEPROP 0 LAST CDS_SEC 1
J 0
(-4725 1500);
PAINT ORANGE (-4725 1500);
DISPLAY INVISIBLE (-4725 1500);
FORCEPROP 2 LAST $SEC 1
J 0
(-4725 1550);
DISPLAY 0.680851 (-4725 1550);
PAINT MONO (-4725 1550);
DISPLAY INVISIBLE (-4725 1550);
FORCEPROP 2 LAST CDS_LOCATION C1R7
J 2
(-4725 1450);
DISPLAY 0.617021 (-4725 1450);
PAINT AQUA (-4725 1450);
DISPLAY INVISIBLE (-4725 1450);
FORCEPROP 1 LAST PATH I70
J 2
(-4725 1500);
DISPLAY 0.978723 (-4725 1500);
PAINT WHITE (-4725 1500);
DISPLAY INVISIBLE (-4725 1500);
FORCEPROP 2 LAST ROOM PCIE_STEERING
J 2
(-4675 1350);
PAINT MONO (-4675 1350);
DISPLAY INVISIBLE (-4675 1350);
FORCEPROP 1 LASTPIN (-4675 1250) $PN 2
J 2
(-4685 1230);
DISPLAY 0.787234 (-4685 1230);
PAINT ORANGE (-4685 1230);
DISPLAY INVISIBLE (-4685 1230);
FORCEPROP 1 LASTPIN (-4675 1450) $PN 1
J 2
(-4685 1430);
DISPLAY 0.787234 (-4685 1430);
PAINT ORANGE (-4685 1430);
DISPLAY INVISIBLE (-4685 1430);
FORCEADD TAP..7
(-4675 1100);
FORCEPROP 3 LASTPIN (-4675 1150) SIG_NAME P3E_OCP_CPU0_PE3_C_TXN<3>
J 0
(-4665 1160);
DISPLAY 0.659574 (-4665 1160);
PAINT MONO (-4665 1160);
DISPLAY INVISIBLE (-4665 1160);
FORCEPROP 1 LASTPIN (-4675 1150) BN 3
R 1
J 0
(-4682 1098);
DISPLAY 0.617021 (-4682 1098);
PAINT GREEN (-4682 1098);
FORCEPROP 2 LAST CDS_LIB mstr_standard
J 0
(-4675 1100);
PAINT ORANGE (-4675 1100);
DISPLAY INVISIBLE (-4675 1100);
FORCEPROP 1 LAST BODY_TYPE PLUMBING
J 0
(-4625 1100);
DISPLAY 2.276596 (-4625 1100);
PAINT GREEN (-4625 1100);
DISPLAY INVISIBLE (-4625 1100);
FORCEPROP 1 LAST HDL_TAP TRUE
J 0
(-4355 970);
DISPLAY 2.276596 (-4355 970);
PAINT GREEN (-4355 970);
DISPLAY INVISIBLE (-4355 970);
FORCEPROP 1 LAST PATH I72
J 0
(-4677 1100);
DISPLAY 0.872340 (-4677 1100);
PAINT GREEN (-4677 1100);
DISPLAY INVISIBLE (-4677 1100);
FORCEADD TAP..7
(-5900 2100);
FORCEPROP 3 LASTPIN (-5900 2150) SIG_NAME P3E_OCP_CPU0_PE3_C_TXP<9>
J 0
(-5890 2160);
DISPLAY 0.659574 (-5890 2160);
PAINT MONO (-5890 2160);
DISPLAY INVISIBLE (-5890 2160);
FORCEPROP 1 LASTPIN (-5900 2150) BN 9
R 1
J 0
(-5907 2098);
DISPLAY 0.617021 (-5907 2098);
PAINT GREEN (-5907 2098);
FORCEPROP 2 LAST CDS_LIB mstr_standard
J 0
(-5900 2100);
PAINT ORANGE (-5900 2100);
DISPLAY INVISIBLE (-5900 2100);
FORCEPROP 1 LAST BODY_TYPE PLUMBING
J 0
(-5850 2100);
DISPLAY 2.276596 (-5850 2100);
PAINT GREEN (-5850 2100);
DISPLAY INVISIBLE (-5850 2100);
FORCEPROP 1 LAST HDL_TAP TRUE
J 0
(-5580 1970);
DISPLAY 2.276596 (-5580 1970);
PAINT GREEN (-5580 1970);
DISPLAY INVISIBLE (-5580 1970);
FORCEPROP 1 LAST PATH I73
J 0
(-5902 2100);
DISPLAY 0.872340 (-5902 2100);
PAINT GREEN (-5902 2100);
DISPLAY INVISIBLE (-5902 2100);
FORCEADD TAP..7
(-5650 1100);
FORCEPROP 3 LASTPIN (-5650 1150) SIG_NAME P3E_OCP_CPU0_PE3_C_TXN<8>
J 0
(-5640 1160);
DISPLAY 0.659574 (-5640 1160);
PAINT MONO (-5640 1160);
DISPLAY INVISIBLE (-5640 1160);
FORCEPROP 1 LASTPIN (-5650 1150) BN 8
R 1
J 0
(-5657 1098);
DISPLAY 0.617021 (-5657 1098);
PAINT GREEN (-5657 1098);
FORCEPROP 2 LAST CDS_LIB mstr_standard
J 0
(-5650 1100);
PAINT ORANGE (-5650 1100);
DISPLAY INVISIBLE (-5650 1100);
FORCEPROP 1 LAST BODY_TYPE PLUMBING
J 0
(-5600 1100);
DISPLAY 2.276596 (-5600 1100);
PAINT GREEN (-5600 1100);
DISPLAY INVISIBLE (-5600 1100);
FORCEPROP 1 LAST HDL_TAP TRUE
J 0
(-5330 970);
DISPLAY 2.276596 (-5330 970);
PAINT GREEN (-5330 970);
DISPLAY INVISIBLE (-5330 970);
FORCEPROP 1 LAST PATH I74
J 0
(-5652 1100);
DISPLAY 0.872340 (-5652 1100);
PAINT GREEN (-5652 1100);
DISPLAY INVISIBLE (-5652 1100);
FORCEADD TAP..3
(-5700 2900);
FORCEPROP 3 LASTPIN (-5700 2850) SIG_NAME P3E_CPU0_PE3_OCP_TXP<8>
J 0
(-5690 2860);
DISPLAY 0.659574 (-5690 2860);
PAINT MONO (-5690 2860);
DISPLAY INVISIBLE (-5690 2860);
FORCEPROP 1 LASTPIN (-5700 2850) BN 8
R 1
J 0
(-5707 2838);
DISPLAY 0.617021 (-5707 2838);
PAINT GREEN (-5707 2838);
FORCEPROP 2 LAST CDS_LIB mstr_standard
J 0
(-5700 2900);
PAINT ORANGE (-5700 2900);
DISPLAY INVISIBLE (-5700 2900);
FORCEPROP 1 LAST BODY_TYPE PLUMBING
J 0
(-5650 2850);
DISPLAY 2.276596 (-5650 2850);
PAINT GREEN (-5650 2850);
DISPLAY INVISIBLE (-5650 2850);
FORCEPROP 1 LAST HDL_TAP TRUE
J 0
(-5380 2770);
DISPLAY 2.276596 (-5380 2770);
PAINT GREEN (-5380 2770);
DISPLAY INVISIBLE (-5380 2770);
FORCEPROP 1 LAST PATH I75
J 0
(-5702 2900);
DISPLAY 0.872340 (-5702 2900);
PAINT GREEN (-5702 2900);
DISPLAY INVISIBLE (-5702 2900);
FORCEADD CAP..1
R 2
(-5700 2650);
FORCEPROP 1 LAST LOCATION C2M14
J 2
(-5750 2750);
DISPLAY 0.617021 (-5750 2750);
PAINT AQUA (-5750 2750);
FORCEPROP 1 LAST PART_NUMBER A36096-155
J 2
(-5750 2500);
DISPLAY 0.617021 (-5750 2500);
PAINT BLUE (-5750 2500);
FORCEPROP 1 LAST VALUE 0.22UF
J 2
(-5750 2700);
DISPLAY 0.617021 (-5750 2700);
PAINT SKYBLUE (-5750 2700);
FORCEPROP 1 LAST TOLERANCE 10%
J 2
(-5750 2600);
DISPLAY 0.617021 (-5750 2600);
PAINT SKYBLUE (-5750 2600);
FORCEPROP 1 LAST PACK_TYPE 0402
J 2
(-5750 2450);
DISPLAY 0.617021 (-5750 2450);
PAINT SKYBLUE (-5750 2450);
FORCEPROP 1 LAST VOLTAGE 16V
J 2
(-5750 2650);
DISPLAY 0.617021 (-5750 2650);
PAINT SKYBLUE (-5750 2650);
FORCEPROP 1 LAST MATERIAL X7R
J 2
(-5750 2550);
DISPLAY 0.617021 (-5750 2550);
PAINT SKYBLUE (-5750 2550);
FORCEPROP 2 LAST CDS_LIB mstr_discrete
J 0
(-5700 2650);
PAINT ORANGE (-5700 2650);
DISPLAY INVISIBLE (-5700 2650);
FORCEPROP 2 LAST BOM_COST IO_SLOT
J 0
(-5950 2800);
PAINT MONO (-5950 2800);
DISPLAY INVISIBLE (-5950 2800);
FORCEPROP 0 LAST CDS_SEC 1
J 0
(-5750 2800);
PAINT ORANGE (-5750 2800);
DISPLAY INVISIBLE (-5750 2800);
FORCEPROP 2 LAST $SEC 1
J 0
(-5750 2850);
DISPLAY 0.680851 (-5750 2850);
PAINT MONO (-5750 2850);
DISPLAY INVISIBLE (-5750 2850);
FORCEPROP 2 LAST CDS_LOCATION C2M14
J 2
(-5750 2750);
DISPLAY 0.617021 (-5750 2750);
PAINT AQUA (-5750 2750);
DISPLAY INVISIBLE (-5750 2750);
FORCEPROP 1 LAST PATH I76
J 2
(-5750 2800);
DISPLAY 0.978723 (-5750 2800);
PAINT WHITE (-5750 2800);
DISPLAY INVISIBLE (-5750 2800);
FORCEPROP 2 LAST ROOM PCIE_STEERING
J 2
(-5700 2650);
PAINT MONO (-5700 2650);
DISPLAY INVISIBLE (-5700 2650);
FORCEPROP 1 LASTPIN (-5700 2550) $PN 2
J 2
(-5710 2530);
DISPLAY 0.787234 (-5710 2530);
PAINT ORANGE (-5710 2530);
DISPLAY INVISIBLE (-5710 2530);
FORCEPROP 1 LASTPIN (-5700 2750) $PN 1
J 2
(-5710 2730);
DISPLAY 0.787234 (-5710 2730);
PAINT ORANGE (-5710 2730);
DISPLAY INVISIBLE (-5710 2730);
FORCEADD TAP..7
(-5700 2100);
FORCEPROP 3 LASTPIN (-5700 2150) SIG_NAME P3E_OCP_CPU0_PE3_C_TXP<8>
J 0
(-5690 2160);
DISPLAY 0.659574 (-5690 2160);
PAINT MONO (-5690 2160);
DISPLAY INVISIBLE (-5690 2160);
FORCEPROP 1 LASTPIN (-5700 2150) BN 8
R 1
J 0
(-5707 2098);
DISPLAY 0.617021 (-5707 2098);
PAINT GREEN (-5707 2098);
FORCEPROP 2 LAST CDS_LIB mstr_standard
J 0
(-5700 2100);
PAINT ORANGE (-5700 2100);
DISPLAY INVISIBLE (-5700 2100);
FORCEPROP 1 LAST BODY_TYPE PLUMBING
J 0
(-5650 2100);
DISPLAY 2.276596 (-5650 2100);
PAINT GREEN (-5650 2100);
DISPLAY INVISIBLE (-5650 2100);
FORCEPROP 1 LAST HDL_TAP TRUE
J 0
(-5380 1970);
DISPLAY 2.276596 (-5380 1970);
PAINT GREEN (-5380 1970);
DISPLAY INVISIBLE (-5380 1970);
FORCEPROP 1 LAST PATH I77
J 0
(-5702 2100);
DISPLAY 0.872340 (-5702 2100);
PAINT GREEN (-5702 2100);
DISPLAY INVISIBLE (-5702 2100);
FORCEADD CAP..1
R 2
(-5900 2350);
FORCEPROP 1 LAST LOCATION C1M18
J 2
(-5950 2450);
DISPLAY 0.617021 (-5950 2450);
PAINT AQUA (-5950 2450);
FORCEPROP 1 LAST PART_NUMBER A36096-155
J 2
(-5950 2200);
DISPLAY 0.617021 (-5950 2200);
PAINT BLUE (-5950 2200);
FORCEPROP 1 LAST VALUE 0.22UF
J 2
(-5950 2400);
DISPLAY 0.617021 (-5950 2400);
PAINT SKYBLUE (-5950 2400);
FORCEPROP 1 LAST TOLERANCE 10%
J 2
(-5950 2300);
DISPLAY 0.617021 (-5950 2300);
PAINT SKYBLUE (-5950 2300);
FORCEPROP 1 LAST VOLTAGE 16V
J 2
(-5950 2350);
DISPLAY 0.617021 (-5950 2350);
PAINT SKYBLUE (-5950 2350);
FORCEPROP 1 LAST MATERIAL X7R
J 2
(-5950 2250);
DISPLAY 0.617021 (-5950 2250);
PAINT SKYBLUE (-5950 2250);
FORCEPROP 1 LAST PACK_TYPE 0402
J 2
(-5950 2150);
DISPLAY 0.617021 (-5950 2150);
PAINT SKYBLUE (-5950 2150);
FORCEPROP 2 LAST CDS_LIB mstr_discrete
J 0
(-5900 2350);
PAINT ORANGE (-5900 2350);
DISPLAY INVISIBLE (-5900 2350);
FORCEPROP 2 LAST BOM_COST IO_SLOT
J 0
(-6150 2500);
PAINT MONO (-6150 2500);
DISPLAY INVISIBLE (-6150 2500);
FORCEPROP 0 LAST CDS_SEC 1
J 0
(-5950 2500);
PAINT ORANGE (-5950 2500);
DISPLAY INVISIBLE (-5950 2500);
FORCEPROP 2 LAST $SEC 1
J 0
(-5950 2550);
DISPLAY 0.680851 (-5950 2550);
PAINT MONO (-5950 2550);
DISPLAY INVISIBLE (-5950 2550);
FORCEPROP 2 LAST CDS_LOCATION C1M18
J 2
(-5950 2450);
DISPLAY 0.617021 (-5950 2450);
PAINT AQUA (-5950 2450);
DISPLAY INVISIBLE (-5950 2450);
FORCEPROP 1 LAST PATH I78
J 2
(-5950 2500);
DISPLAY 0.978723 (-5950 2500);
PAINT WHITE (-5950 2500);
DISPLAY INVISIBLE (-5950 2500);
FORCEPROP 2 LAST ROOM PCIE_STEERING
J 2
(-5900 2350);
PAINT MONO (-5900 2350);
DISPLAY INVISIBLE (-5900 2350);
FORCEPROP 1 LASTPIN (-5900 2250) $PN 2
J 2
(-5910 2230);
DISPLAY 0.787234 (-5910 2230);
PAINT ORANGE (-5910 2230);
DISPLAY INVISIBLE (-5910 2230);
FORCEPROP 1 LASTPIN (-5900 2450) $PN 1
J 2
(-5910 2430);
DISPLAY 0.787234 (-5910 2430);
PAINT ORANGE (-5910 2430);
DISPLAY INVISIBLE (-5910 2430);
FORCEADD TAP..3
(-5900 2900);
FORCEPROP 3 LASTPIN (-5900 2850) SIG_NAME P3E_CPU0_PE3_OCP_TXP<9>
J 0
(-5890 2860);
DISPLAY 0.659574 (-5890 2860);
PAINT MONO (-5890 2860);
DISPLAY INVISIBLE (-5890 2860);
FORCEPROP 1 LASTPIN (-5900 2850) BN 9
R 1
J 0
(-5907 2838);
DISPLAY 0.617021 (-5907 2838);
PAINT GREEN (-5907 2838);
FORCEPROP 2 LAST CDS_LIB mstr_standard
J 0
(-5900 2900);
PAINT ORANGE (-5900 2900);
DISPLAY INVISIBLE (-5900 2900);
FORCEPROP 1 LAST BODY_TYPE PLUMBING
J 0
(-5850 2850);
DISPLAY 2.276596 (-5850 2850);
PAINT GREEN (-5850 2850);
DISPLAY INVISIBLE (-5850 2850);
FORCEPROP 1 LAST HDL_TAP TRUE
J 0
(-5580 2770);
DISPLAY 2.276596 (-5580 2770);
PAINT GREEN (-5580 2770);
DISPLAY INVISIBLE (-5580 2770);
FORCEPROP 1 LAST PATH I79
J 0
(-5902 2900);
DISPLAY 0.872340 (-5902 2900);
PAINT GREEN (-5902 2900);
DISPLAY INVISIBLE (-5902 2900);
FORCEADD TAP..3
(-6100 2900);
FORCEPROP 3 LASTPIN (-6100 2850) SIG_NAME P3E_CPU0_PE3_OCP_TXP<10>
J 0
(-6090 2860);
DISPLAY 0.659574 (-6090 2860);
PAINT MONO (-6090 2860);
DISPLAY INVISIBLE (-6090 2860);
FORCEPROP 1 LASTPIN (-6100 2850) BN 10
R 1
J 0
(-6107 2838);
DISPLAY 0.617021 (-6107 2838);
PAINT GREEN (-6107 2838);
FORCEPROP 2 LAST CDS_LIB mstr_standard
J 0
(-6100 2900);
PAINT ORANGE (-6100 2900);
DISPLAY INVISIBLE (-6100 2900);
FORCEPROP 1 LAST BODY_TYPE PLUMBING
J 0
(-6050 2850);
DISPLAY 2.276596 (-6050 2850);
PAINT GREEN (-6050 2850);
DISPLAY INVISIBLE (-6050 2850);
FORCEPROP 1 LAST HDL_TAP TRUE
J 0
(-5780 2770);
DISPLAY 2.276596 (-5780 2770);
PAINT GREEN (-5780 2770);
DISPLAY INVISIBLE (-5780 2770);
FORCEPROP 1 LAST PATH I80
J 0
(-6102 2900);
DISPLAY 0.872340 (-6102 2900);
PAINT GREEN (-6102 2900);
DISPLAY INVISIBLE (-6102 2900);
FORCEADD TAP..3
(-6300 2900);
FORCEPROP 3 LASTPIN (-6300 2850) SIG_NAME P3E_CPU0_PE3_OCP_TXP<11>
J 0
(-6290 2860);
DISPLAY 0.659574 (-6290 2860);
PAINT MONO (-6290 2860);
DISPLAY INVISIBLE (-6290 2860);
FORCEPROP 1 LASTPIN (-6300 2850) BN 11
R 1
J 0
(-6307 2838);
DISPLAY 0.617021 (-6307 2838);
PAINT GREEN (-6307 2838);
FORCEPROP 2 LAST CDS_LIB mstr_standard
J 0
(-6300 2900);
PAINT ORANGE (-6300 2900);
DISPLAY INVISIBLE (-6300 2900);
FORCEPROP 1 LAST BODY_TYPE PLUMBING
J 0
(-6250 2850);
DISPLAY 2.276596 (-6250 2850);
PAINT GREEN (-6250 2850);
DISPLAY INVISIBLE (-6250 2850);
FORCEPROP 1 LAST HDL_TAP TRUE
J 0
(-5980 2770);
DISPLAY 2.276596 (-5980 2770);
PAINT GREEN (-5980 2770);
DISPLAY INVISIBLE (-5980 2770);
FORCEPROP 1 LAST PATH I81
J 0
(-6302 2900);
DISPLAY 0.872340 (-6302 2900);
PAINT GREEN (-6302 2900);
DISPLAY INVISIBLE (-6302 2900);
FORCEADD CAP..1
R 2
(-6100 2650);
FORCEPROP 1 LAST LOCATION C1M16
J 2
(-6150 2750);
DISPLAY 0.617021 (-6150 2750);
PAINT AQUA (-6150 2750);
FORCEPROP 1 LAST PART_NUMBER A36096-155
J 2
(-6150 2500);
DISPLAY 0.617021 (-6150 2500);
PAINT BLUE (-6150 2500);
FORCEPROP 1 LAST VALUE 0.22UF
J 2
(-6150 2700);
DISPLAY 0.617021 (-6150 2700);
PAINT SKYBLUE (-6150 2700);
FORCEPROP 1 LAST TOLERANCE 10%
J 2
(-6150 2600);
DISPLAY 0.617021 (-6150 2600);
PAINT SKYBLUE (-6150 2600);
FORCEPROP 1 LAST PACK_TYPE 0402
J 2
(-6150 2450);
DISPLAY 0.617021 (-6150 2450);
PAINT SKYBLUE (-6150 2450);
FORCEPROP 1 LAST VOLTAGE 16V
J 2
(-6150 2650);
DISPLAY 0.617021 (-6150 2650);
PAINT SKYBLUE (-6150 2650);
FORCEPROP 1 LAST MATERIAL X7R
J 2
(-6150 2550);
DISPLAY 0.617021 (-6150 2550);
PAINT SKYBLUE (-6150 2550);
FORCEPROP 2 LAST CDS_LIB mstr_discrete
J 0
(-6100 2650);
PAINT ORANGE (-6100 2650);
DISPLAY INVISIBLE (-6100 2650);
FORCEPROP 2 LAST BOM_COST IO_SLOT
J 0
(-6350 2800);
PAINT MONO (-6350 2800);
DISPLAY INVISIBLE (-6350 2800);
FORCEPROP 0 LAST CDS_SEC 1
J 0
(-6150 2800);
PAINT ORANGE (-6150 2800);
DISPLAY INVISIBLE (-6150 2800);
FORCEPROP 2 LAST $SEC 1
J 0
(-6150 2850);
DISPLAY 0.680851 (-6150 2850);
PAINT MONO (-6150 2850);
DISPLAY INVISIBLE (-6150 2850);
FORCEPROP 2 LAST CDS_LOCATION C1M16
J 2
(-6150 2750);
DISPLAY 0.617021 (-6150 2750);
PAINT AQUA (-6150 2750);
DISPLAY INVISIBLE (-6150 2750);
FORCEPROP 1 LAST PATH I82
J 2
(-6150 2800);
DISPLAY 0.978723 (-6150 2800);
PAINT WHITE (-6150 2800);
DISPLAY INVISIBLE (-6150 2800);
FORCEPROP 2 LAST ROOM PCIE_STEERING
J 2
(-6100 2650);
PAINT MONO (-6100 2650);
DISPLAY INVISIBLE (-6100 2650);
FORCEPROP 1 LASTPIN (-6100 2550) $PN 2
J 2
(-6110 2530);
DISPLAY 0.787234 (-6110 2530);
PAINT ORANGE (-6110 2530);
DISPLAY INVISIBLE (-6110 2530);
FORCEPROP 1 LASTPIN (-6100 2750) $PN 1
J 2
(-6110 2730);
DISPLAY 0.787234 (-6110 2730);
PAINT ORANGE (-6110 2730);
DISPLAY INVISIBLE (-6110 2730);
FORCEADD TAP..7
(-6100 2100);
FORCEPROP 3 LASTPIN (-6100 2150) SIG_NAME P3E_OCP_CPU0_PE3_C_TXP<10>
J 0
(-6090 2160);
DISPLAY 0.659574 (-6090 2160);
PAINT MONO (-6090 2160);
DISPLAY INVISIBLE (-6090 2160);
FORCEPROP 1 LASTPIN (-6100 2150) BN 10
R 1
J 0
(-6107 2098);
DISPLAY 0.617021 (-6107 2098);
PAINT GREEN (-6107 2098);
FORCEPROP 2 LAST CDS_LIB mstr_standard
J 0
(-6100 2100);
PAINT ORANGE (-6100 2100);
DISPLAY INVISIBLE (-6100 2100);
FORCEPROP 1 LAST BODY_TYPE PLUMBING
J 0
(-6050 2100);
DISPLAY 2.276596 (-6050 2100);
PAINT GREEN (-6050 2100);
DISPLAY INVISIBLE (-6050 2100);
FORCEPROP 1 LAST HDL_TAP TRUE
J 0
(-5780 1970);
DISPLAY 2.276596 (-5780 1970);
PAINT GREEN (-5780 1970);
DISPLAY INVISIBLE (-5780 1970);
FORCEPROP 1 LAST PATH I83
J 0
(-6102 2100);
DISPLAY 0.872340 (-6102 2100);
PAINT GREEN (-6102 2100);
DISPLAY INVISIBLE (-6102 2100);
FORCEADD TAP..7
(-6300 2100);
FORCEPROP 3 LASTPIN (-6300 2150) SIG_NAME P3E_OCP_CPU0_PE3_C_TXP<11>
J 0
(-6290 2160);
DISPLAY 0.659574 (-6290 2160);
PAINT MONO (-6290 2160);
DISPLAY INVISIBLE (-6290 2160);
FORCEPROP 1 LASTPIN (-6300 2150) BN 11
R 1
J 0
(-6307 2098);
DISPLAY 0.617021 (-6307 2098);
PAINT GREEN (-6307 2098);
FORCEPROP 2 LAST CDS_LIB mstr_standard
J 0
(-6300 2100);
PAINT ORANGE (-6300 2100);
DISPLAY INVISIBLE (-6300 2100);
FORCEPROP 1 LAST BODY_TYPE PLUMBING
J 0
(-6250 2100);
DISPLAY 2.276596 (-6250 2100);
PAINT GREEN (-6250 2100);
DISPLAY INVISIBLE (-6250 2100);
FORCEPROP 1 LAST HDL_TAP TRUE
J 0
(-5980 1970);
DISPLAY 2.276596 (-5980 1970);
PAINT GREEN (-5980 1970);
DISPLAY INVISIBLE (-5980 1970);
FORCEPROP 1 LAST PATH I84
J 0
(-6302 2100);
DISPLAY 0.872340 (-6302 2100);
PAINT GREEN (-6302 2100);
DISPLAY INVISIBLE (-6302 2100);
FORCEADD CAP..1
R 2
(-6300 2350);
FORCEPROP 1 LAST LOCATION C1M14
J 2
(-6350 2450);
DISPLAY 0.617021 (-6350 2450);
PAINT AQUA (-6350 2450);
FORCEPROP 1 LAST PART_NUMBER A36096-155
J 2
(-6350 2200);
DISPLAY 0.617021 (-6350 2200);
PAINT BLUE (-6350 2200);
FORCEPROP 1 LAST VALUE 0.22UF
J 2
(-6350 2400);
DISPLAY 0.617021 (-6350 2400);
PAINT SKYBLUE (-6350 2400);
FORCEPROP 1 LAST PACK_TYPE 0402
J 2
(-6350 2150);
DISPLAY 0.617021 (-6350 2150);
PAINT SKYBLUE (-6350 2150);
FORCEPROP 1 LAST MATERIAL X7R
J 2
(-6350 2250);
DISPLAY 0.617021 (-6350 2250);
PAINT SKYBLUE (-6350 2250);
FORCEPROP 1 LAST VOLTAGE 16V
J 2
(-6350 2350);
DISPLAY 0.617021 (-6350 2350);
PAINT SKYBLUE (-6350 2350);
FORCEPROP 1 LAST TOLERANCE 10%
J 2
(-6350 2300);
DISPLAY 0.617021 (-6350 2300);
PAINT SKYBLUE (-6350 2300);
FORCEPROP 2 LAST CDS_LIB mstr_discrete
J 0
(-6300 2350);
PAINT ORANGE (-6300 2350);
DISPLAY INVISIBLE (-6300 2350);
FORCEPROP 2 LAST BOM_COST IO_SLOT
J 0
(-6550 2500);
PAINT MONO (-6550 2500);
DISPLAY INVISIBLE (-6550 2500);
FORCEPROP 0 LAST CDS_SEC 1
J 0
(-6350 2500);
PAINT ORANGE (-6350 2500);
DISPLAY INVISIBLE (-6350 2500);
FORCEPROP 2 LAST $SEC 1
J 0
(-6350 2550);
DISPLAY 0.680851 (-6350 2550);
PAINT MONO (-6350 2550);
DISPLAY INVISIBLE (-6350 2550);
FORCEPROP 2 LAST CDS_LOCATION C1M14
J 2
(-6350 2450);
DISPLAY 0.617021 (-6350 2450);
PAINT AQUA (-6350 2450);
DISPLAY INVISIBLE (-6350 2450);
FORCEPROP 1 LAST PATH I85
J 2
(-6350 2500);
DISPLAY 0.978723 (-6350 2500);
PAINT WHITE (-6350 2500);
DISPLAY INVISIBLE (-6350 2500);
FORCEPROP 2 LAST ROOM PCIE_STEERING
J 2
(-6300 2350);
PAINT MONO (-6300 2350);
DISPLAY INVISIBLE (-6300 2350);
FORCEPROP 1 LASTPIN (-6300 2250) $PN 2
J 2
(-6310 2230);
DISPLAY 0.787234 (-6310 2230);
PAINT ORANGE (-6310 2230);
DISPLAY INVISIBLE (-6310 2230);
FORCEPROP 1 LASTPIN (-6300 2450) $PN 1
J 2
(-6310 2430);
DISPLAY 0.787234 (-6310 2430);
PAINT ORANGE (-6310 2430);
DISPLAY INVISIBLE (-6310 2430);
FORCEADD CAP..1
R 2
(-5650 1650);
FORCEPROP 1 LAST LOCATION C2M15
J 2
(-5700 1750);
DISPLAY 0.617021 (-5700 1750);
PAINT AQUA (-5700 1750);
FORCEPROP 1 LAST PART_NUMBER A36096-155
J 2
(-5700 1500);
DISPLAY 0.617021 (-5700 1500);
PAINT BLUE (-5700 1500);
FORCEPROP 1 LAST VALUE 0.22UF
J 2
(-5700 1700);
DISPLAY 0.617021 (-5700 1700);
PAINT SKYBLUE (-5700 1700);
FORCEPROP 1 LAST TOLERANCE 10%
J 2
(-5700 1600);
DISPLAY 0.617021 (-5700 1600);
PAINT SKYBLUE (-5700 1600);
FORCEPROP 1 LAST PACK_TYPE 0402
J 2
(-5700 1450);
DISPLAY 0.617021 (-5700 1450);
PAINT SKYBLUE (-5700 1450);
FORCEPROP 1 LAST VOLTAGE 16V
J 2
(-5700 1650);
DISPLAY 0.617021 (-5700 1650);
PAINT SKYBLUE (-5700 1650);
FORCEPROP 1 LAST MATERIAL X7R
J 2
(-5700 1550);
DISPLAY 0.617021 (-5700 1550);
PAINT SKYBLUE (-5700 1550);
FORCEPROP 2 LAST CDS_LIB mstr_discrete
J 0
(-5650 1650);
PAINT ORANGE (-5650 1650);
DISPLAY INVISIBLE (-5650 1650);
FORCEPROP 2 LAST BOM_COST IO_SLOT
J 0
(-5900 1800);
PAINT MONO (-5900 1800);
DISPLAY INVISIBLE (-5900 1800);
FORCEPROP 0 LAST CDS_SEC 1
J 0
(-5700 1800);
PAINT ORANGE (-5700 1800);
DISPLAY INVISIBLE (-5700 1800);
FORCEPROP 2 LAST $SEC 1
J 0
(-5700 1850);
DISPLAY 0.680851 (-5700 1850);
PAINT MONO (-5700 1850);
DISPLAY INVISIBLE (-5700 1850);
FORCEPROP 2 LAST CDS_LOCATION C2M15
J 2
(-5700 1750);
DISPLAY 0.617021 (-5700 1750);
PAINT AQUA (-5700 1750);
DISPLAY INVISIBLE (-5700 1750);
FORCEPROP 1 LAST PATH I86
J 2
(-5700 1800);
DISPLAY 0.978723 (-5700 1800);
PAINT WHITE (-5700 1800);
DISPLAY INVISIBLE (-5700 1800);
FORCEPROP 2 LAST ROOM PCIE_STEERING
J 2
(-5650 1650);
PAINT MONO (-5650 1650);
DISPLAY INVISIBLE (-5650 1650);
FORCEPROP 1 LASTPIN (-5650 1550) $PN 2
J 2
(-5660 1530);
DISPLAY 0.787234 (-5660 1530);
PAINT ORANGE (-5660 1530);
DISPLAY INVISIBLE (-5660 1530);
FORCEPROP 1 LASTPIN (-5650 1750) $PN 1
J 2
(-5660 1730);
DISPLAY 0.787234 (-5660 1730);
PAINT ORANGE (-5660 1730);
DISPLAY INVISIBLE (-5660 1730);
FORCEADD TAP..3
(-5650 1900);
FORCEPROP 3 LASTPIN (-5650 1850) SIG_NAME P3E_CPU0_PE3_OCP_TXN<8>
J 0
(-5640 1860);
DISPLAY 0.659574 (-5640 1860);
PAINT MONO (-5640 1860);
DISPLAY INVISIBLE (-5640 1860);
FORCEPROP 1 LASTPIN (-5650 1850) BN 8
R 1
J 0
(-5657 1838);
DISPLAY 0.617021 (-5657 1838);
PAINT GREEN (-5657 1838);
FORCEPROP 2 LAST CDS_LIB mstr_standard
J 0
(-5650 1900);
PAINT ORANGE (-5650 1900);
DISPLAY INVISIBLE (-5650 1900);
FORCEPROP 1 LAST BODY_TYPE PLUMBING
J 0
(-5600 1850);
DISPLAY 2.276596 (-5600 1850);
PAINT GREEN (-5600 1850);
DISPLAY INVISIBLE (-5600 1850);
FORCEPROP 1 LAST HDL_TAP TRUE
J 0
(-5330 1770);
DISPLAY 2.276596 (-5330 1770);
PAINT GREEN (-5330 1770);
DISPLAY INVISIBLE (-5330 1770);
FORCEPROP 1 LAST PATH I87
J 0
(-5652 1900);
DISPLAY 0.872340 (-5652 1900);
PAINT GREEN (-5652 1900);
DISPLAY INVISIBLE (-5652 1900);
FORCEADD TAP..3
(-5850 1900);
FORCEPROP 3 LASTPIN (-5850 1850) SIG_NAME P3E_CPU0_PE3_OCP_TXN<9>
J 0
(-5840 1860);
DISPLAY 0.659574 (-5840 1860);
PAINT MONO (-5840 1860);
DISPLAY INVISIBLE (-5840 1860);
FORCEPROP 1 LASTPIN (-5850 1850) BN 9
R 1
J 0
(-5857 1838);
DISPLAY 0.617021 (-5857 1838);
PAINT GREEN (-5857 1838);
FORCEPROP 2 LAST CDS_LIB mstr_standard
J 0
(-5850 1900);
PAINT ORANGE (-5850 1900);
DISPLAY INVISIBLE (-5850 1900);
FORCEPROP 1 LAST BODY_TYPE PLUMBING
J 0
(-5800 1850);
DISPLAY 2.276596 (-5800 1850);
PAINT GREEN (-5800 1850);
DISPLAY INVISIBLE (-5800 1850);
FORCEPROP 1 LAST HDL_TAP TRUE
J 0
(-5530 1770);
DISPLAY 2.276596 (-5530 1770);
PAINT GREEN (-5530 1770);
DISPLAY INVISIBLE (-5530 1770);
FORCEPROP 1 LAST PATH I88
J 0
(-5852 1900);
DISPLAY 0.872340 (-5852 1900);
PAINT GREEN (-5852 1900);
DISPLAY INVISIBLE (-5852 1900);
FORCEADD TAP..7
(-5850 1100);
FORCEPROP 3 LASTPIN (-5850 1150) SIG_NAME P3E_OCP_CPU0_PE3_C_TXN<9>
J 0
(-5840 1160);
DISPLAY 0.659574 (-5840 1160);
PAINT MONO (-5840 1160);
DISPLAY INVISIBLE (-5840 1160);
FORCEPROP 1 LASTPIN (-5850 1150) BN 9
R 1
J 0
(-5857 1098);
DISPLAY 0.617021 (-5857 1098);
PAINT GREEN (-5857 1098);
FORCEPROP 2 LAST CDS_LIB mstr_standard
J 0
(-5850 1100);
PAINT ORANGE (-5850 1100);
DISPLAY INVISIBLE (-5850 1100);
FORCEPROP 1 LAST BODY_TYPE PLUMBING
J 0
(-5800 1100);
DISPLAY 2.276596 (-5800 1100);
PAINT GREEN (-5800 1100);
DISPLAY INVISIBLE (-5800 1100);
FORCEPROP 1 LAST HDL_TAP TRUE
J 0
(-5530 970);
DISPLAY 2.276596 (-5530 970);
PAINT GREEN (-5530 970);
DISPLAY INVISIBLE (-5530 970);
FORCEPROP 1 LAST PATH I89
J 0
(-5852 1100);
DISPLAY 0.872340 (-5852 1100);
PAINT GREEN (-5852 1100);
DISPLAY INVISIBLE (-5852 1100);
FORCEADD TAP..3
(-4100 2900);
FORCEPROP 3 LASTPIN (-4100 2850) SIG_NAME P3E_CPU0_PE3_OCP_TXP<0>
J 0
(-4090 2860);
DISPLAY 0.659574 (-4090 2860);
PAINT MONO (-4090 2860);
DISPLAY INVISIBLE (-4090 2860);
FORCEPROP 1 LASTPIN (-4100 2850) BN 0
R 1
J 0
(-4107 2838);
DISPLAY 0.617021 (-4107 2838);
PAINT GREEN (-4107 2838);
FORCEPROP 2 LAST CDS_LIB mstr_standard
J 0
(-4100 2900);
PAINT ORANGE (-4100 2900);
DISPLAY INVISIBLE (-4100 2900);
FORCEPROP 1 LAST BODY_TYPE PLUMBING
J 0
(-4050 2850);
DISPLAY 2.276596 (-4050 2850);
PAINT GREEN (-4050 2850);
DISPLAY INVISIBLE (-4050 2850);
FORCEPROP 1 LAST HDL_TAP TRUE
J 0
(-3780 2770);
DISPLAY 2.276596 (-3780 2770);
PAINT GREEN (-3780 2770);
DISPLAY INVISIBLE (-3780 2770);
FORCEPROP 1 LAST PATH I9
J 0
(-4102 2900);
DISPLAY 0.872340 (-4102 2900);
PAINT GREEN (-4102 2900);
DISPLAY INVISIBLE (-4102 2900);
FORCEADD CAP..1
R 2
(-5850 1350);
FORCEPROP 1 LAST LOCATION C1M19
J 2
(-5900 1450);
DISPLAY 0.617021 (-5900 1450);
PAINT AQUA (-5900 1450);
FORCEPROP 1 LAST PART_NUMBER A36096-155
J 2
(-5900 1200);
DISPLAY 0.617021 (-5900 1200);
PAINT BLUE (-5900 1200);
FORCEPROP 1 LAST VALUE 0.22UF
J 2
(-5900 1400);
DISPLAY 0.617021 (-5900 1400);
PAINT SKYBLUE (-5900 1400);
FORCEPROP 1 LAST TOLERANCE 10%
J 2
(-5900 1300);
DISPLAY 0.617021 (-5900 1300);
PAINT SKYBLUE (-5900 1300);
FORCEPROP 1 LAST PACK_TYPE 0402
J 2
(-5900 1150);
DISPLAY 0.617021 (-5900 1150);
PAINT SKYBLUE (-5900 1150);
FORCEPROP 1 LAST VOLTAGE 16V
J 2
(-5900 1350);
DISPLAY 0.617021 (-5900 1350);
PAINT SKYBLUE (-5900 1350);
FORCEPROP 1 LAST MATERIAL X7R
J 2
(-5900 1250);
DISPLAY 0.617021 (-5900 1250);
PAINT SKYBLUE (-5900 1250);
FORCEPROP 2 LAST CDS_LIB mstr_discrete
J 0
(-5850 1350);
PAINT ORANGE (-5850 1350);
DISPLAY INVISIBLE (-5850 1350);
FORCEPROP 2 LAST BOM_COST IO_SLOT
J 0
(-6100 1500);
PAINT MONO (-6100 1500);
DISPLAY INVISIBLE (-6100 1500);
FORCEPROP 0 LAST CDS_SEC 1
J 0
(-5900 1500);
PAINT ORANGE (-5900 1500);
DISPLAY INVISIBLE (-5900 1500);
FORCEPROP 2 LAST $SEC 1
J 0
(-5900 1550);
DISPLAY 0.680851 (-5900 1550);
PAINT MONO (-5900 1550);
DISPLAY INVISIBLE (-5900 1550);
FORCEPROP 2 LAST CDS_LOCATION C1M19
J 2
(-5900 1450);
DISPLAY 0.617021 (-5900 1450);
PAINT AQUA (-5900 1450);
DISPLAY INVISIBLE (-5900 1450);
FORCEPROP 1 LAST PATH I90
J 2
(-5900 1500);
DISPLAY 0.978723 (-5900 1500);
PAINT WHITE (-5900 1500);
DISPLAY INVISIBLE (-5900 1500);
FORCEPROP 2 LAST ROOM PCIE_STEERING
J 2
(-5850 1350);
PAINT MONO (-5850 1350);
DISPLAY INVISIBLE (-5850 1350);
FORCEPROP 1 LASTPIN (-5850 1250) $PN 2
J 2
(-5860 1230);
DISPLAY 0.787234 (-5860 1230);
PAINT ORANGE (-5860 1230);
DISPLAY INVISIBLE (-5860 1230);
FORCEPROP 1 LASTPIN (-5850 1450) $PN 1
J 2
(-5860 1430);
DISPLAY 0.787234 (-5860 1430);
PAINT ORANGE (-5860 1430);
DISPLAY INVISIBLE (-5860 1430);
FORCEADD TAP..3
(-6050 1900);
FORCEPROP 3 LASTPIN (-6050 1850) SIG_NAME P3E_CPU0_PE3_OCP_TXN<10>
J 0
(-6040 1860);
DISPLAY 0.659574 (-6040 1860);
PAINT MONO (-6040 1860);
DISPLAY INVISIBLE (-6040 1860);
FORCEPROP 1 LASTPIN (-6050 1850) BN 10
R 1
J 0
(-6057 1838);
DISPLAY 0.617021 (-6057 1838);
PAINT GREEN (-6057 1838);
FORCEPROP 2 LAST CDS_LIB mstr_standard
J 0
(-6050 1900);
PAINT ORANGE (-6050 1900);
DISPLAY INVISIBLE (-6050 1900);
FORCEPROP 1 LAST BODY_TYPE PLUMBING
J 0
(-6000 1850);
DISPLAY 2.276596 (-6000 1850);
PAINT GREEN (-6000 1850);
DISPLAY INVISIBLE (-6000 1850);
FORCEPROP 1 LAST HDL_TAP TRUE
J 0
(-5730 1770);
DISPLAY 2.276596 (-5730 1770);
PAINT GREEN (-5730 1770);
DISPLAY INVISIBLE (-5730 1770);
FORCEPROP 1 LAST PATH I91
J 0
(-6052 1900);
DISPLAY 0.872340 (-6052 1900);
PAINT GREEN (-6052 1900);
DISPLAY INVISIBLE (-6052 1900);
FORCEADD CAP..1
R 2
(-6050 1650);
FORCEPROP 1 LAST LOCATION C1M17
J 2
(-6100 1750);
DISPLAY 0.617021 (-6100 1750);
PAINT AQUA (-6100 1750);
FORCEPROP 1 LAST PART_NUMBER A36096-155
J 2
(-6100 1500);
DISPLAY 0.617021 (-6100 1500);
PAINT BLUE (-6100 1500);
FORCEPROP 1 LAST VALUE 0.22UF
J 2
(-6100 1700);
DISPLAY 0.617021 (-6100 1700);
PAINT SKYBLUE (-6100 1700);
FORCEPROP 1 LAST TOLERANCE 10%
J 2
(-6100 1600);
DISPLAY 0.617021 (-6100 1600);
PAINT SKYBLUE (-6100 1600);
FORCEPROP 1 LAST PACK_TYPE 0402
J 2
(-6100 1450);
DISPLAY 0.617021 (-6100 1450);
PAINT SKYBLUE (-6100 1450);
FORCEPROP 1 LAST VOLTAGE 16V
J 2
(-6100 1650);
DISPLAY 0.617021 (-6100 1650);
PAINT SKYBLUE (-6100 1650);
FORCEPROP 1 LAST MATERIAL X7R
J 2
(-6100 1550);
DISPLAY 0.617021 (-6100 1550);
PAINT SKYBLUE (-6100 1550);
FORCEPROP 2 LAST CDS_LIB mstr_discrete
J 0
(-6050 1650);
PAINT ORANGE (-6050 1650);
DISPLAY INVISIBLE (-6050 1650);
FORCEPROP 2 LAST BOM_COST IO_SLOT
J 0
(-6300 1800);
PAINT MONO (-6300 1800);
DISPLAY INVISIBLE (-6300 1800);
FORCEPROP 0 LAST CDS_SEC 1
J 0
(-6100 1800);
PAINT ORANGE (-6100 1800);
DISPLAY INVISIBLE (-6100 1800);
FORCEPROP 2 LAST $SEC 1
J 0
(-6100 1850);
DISPLAY 0.680851 (-6100 1850);
PAINT MONO (-6100 1850);
DISPLAY INVISIBLE (-6100 1850);
FORCEPROP 2 LAST CDS_LOCATION C1M17
J 2
(-6100 1750);
DISPLAY 0.617021 (-6100 1750);
PAINT AQUA (-6100 1750);
DISPLAY INVISIBLE (-6100 1750);
FORCEPROP 1 LAST PATH I92
J 2
(-6100 1800);
DISPLAY 0.978723 (-6100 1800);
PAINT WHITE (-6100 1800);
DISPLAY INVISIBLE (-6100 1800);
FORCEPROP 2 LAST ROOM PCIE_STEERING
J 2
(-6050 1650);
PAINT MONO (-6050 1650);
DISPLAY INVISIBLE (-6050 1650);
FORCEPROP 1 LASTPIN (-6050 1550) $PN 2
J 2
(-6060 1530);
DISPLAY 0.787234 (-6060 1530);
PAINT ORANGE (-6060 1530);
DISPLAY INVISIBLE (-6060 1530);
FORCEPROP 1 LASTPIN (-6050 1750) $PN 1
J 2
(-6060 1730);
DISPLAY 0.787234 (-6060 1730);
PAINT ORANGE (-6060 1730);
DISPLAY INVISIBLE (-6060 1730);
FORCEADD TAP..3
(-6250 1900);
FORCEPROP 3 LASTPIN (-6250 1850) SIG_NAME P3E_CPU0_PE3_OCP_TXN<11>
J 0
(-6240 1860);
DISPLAY 0.659574 (-6240 1860);
PAINT MONO (-6240 1860);
DISPLAY INVISIBLE (-6240 1860);
FORCEPROP 1 LASTPIN (-6250 1850) BN 11
R 1
J 0
(-6257 1838);
DISPLAY 0.617021 (-6257 1838);
PAINT GREEN (-6257 1838);
FORCEPROP 2 LAST CDS_LIB mstr_standard
J 0
(-6250 1900);
PAINT ORANGE (-6250 1900);
DISPLAY INVISIBLE (-6250 1900);
FORCEPROP 1 LAST BODY_TYPE PLUMBING
J 0
(-6200 1850);
DISPLAY 2.276596 (-6200 1850);
PAINT GREEN (-6200 1850);
DISPLAY INVISIBLE (-6200 1850);
FORCEPROP 1 LAST HDL_TAP TRUE
J 0
(-5930 1770);
DISPLAY 2.276596 (-5930 1770);
PAINT GREEN (-5930 1770);
DISPLAY INVISIBLE (-5930 1770);
FORCEPROP 1 LAST PATH I93
J 0
(-6252 1900);
DISPLAY 0.872340 (-6252 1900);
PAINT GREEN (-6252 1900);
DISPLAY INVISIBLE (-6252 1900);
FORCEADD TAP..7
(-6050 1100);
FORCEPROP 3 LASTPIN (-6050 1150) SIG_NAME P3E_OCP_CPU0_PE3_C_TXN<10>
J 0
(-6040 1160);
DISPLAY 0.659574 (-6040 1160);
PAINT MONO (-6040 1160);
DISPLAY INVISIBLE (-6040 1160);
FORCEPROP 1 LASTPIN (-6050 1150) BN 10
R 1
J 0
(-6057 1098);
DISPLAY 0.617021 (-6057 1098);
PAINT GREEN (-6057 1098);
FORCEPROP 2 LAST CDS_LIB mstr_standard
J 0
(-6050 1100);
PAINT ORANGE (-6050 1100);
DISPLAY INVISIBLE (-6050 1100);
FORCEPROP 1 LAST BODY_TYPE PLUMBING
J 0
(-6000 1100);
DISPLAY 2.276596 (-6000 1100);
PAINT GREEN (-6000 1100);
DISPLAY INVISIBLE (-6000 1100);
FORCEPROP 1 LAST HDL_TAP TRUE
J 0
(-5730 970);
DISPLAY 2.276596 (-5730 970);
PAINT GREEN (-5730 970);
DISPLAY INVISIBLE (-5730 970);
FORCEPROP 1 LAST PATH I94
J 0
(-6052 1100);
DISPLAY 0.872340 (-6052 1100);
PAINT GREEN (-6052 1100);
DISPLAY INVISIBLE (-6052 1100);
FORCEADD CAP..1
R 2
(-6250 1350);
FORCEPROP 1 LAST LOCATION C1M15
J 2
(-6300 1450);
DISPLAY 0.617021 (-6300 1450);
PAINT AQUA (-6300 1450);
FORCEPROP 1 LAST PART_NUMBER A36096-155
J 2
(-6300 1200);
DISPLAY 0.617021 (-6300 1200);
PAINT BLUE (-6300 1200);
FORCEPROP 1 LAST VALUE 0.22UF
J 2
(-6300 1400);
DISPLAY 0.617021 (-6300 1400);
PAINT SKYBLUE (-6300 1400);
FORCEPROP 1 LAST TOLERANCE 10%
J 2
(-6300 1300);
DISPLAY 0.617021 (-6300 1300);
PAINT SKYBLUE (-6300 1300);
FORCEPROP 1 LAST PACK_TYPE 0402
J 2
(-6300 1150);
DISPLAY 0.617021 (-6300 1150);
PAINT SKYBLUE (-6300 1150);
FORCEPROP 1 LAST VOLTAGE 16V
J 2
(-6300 1350);
DISPLAY 0.617021 (-6300 1350);
PAINT SKYBLUE (-6300 1350);
FORCEPROP 1 LAST MATERIAL X7R
J 2
(-6300 1250);
DISPLAY 0.617021 (-6300 1250);
PAINT SKYBLUE (-6300 1250);
FORCEPROP 2 LAST CDS_LIB mstr_discrete
J 0
(-6250 1350);
PAINT ORANGE (-6250 1350);
DISPLAY INVISIBLE (-6250 1350);
FORCEPROP 2 LAST BOM_COST IO_SLOT
J 0
(-6500 1500);
PAINT MONO (-6500 1500);
DISPLAY INVISIBLE (-6500 1500);
FORCEPROP 0 LAST CDS_SEC 1
J 0
(-6300 1500);
PAINT ORANGE (-6300 1500);
DISPLAY INVISIBLE (-6300 1500);
FORCEPROP 2 LAST $SEC 1
J 0
(-6300 1550);
DISPLAY 0.680851 (-6300 1550);
PAINT MONO (-6300 1550);
DISPLAY INVISIBLE (-6300 1550);
FORCEPROP 2 LAST CDS_LOCATION C1M15
J 2
(-6300 1450);
DISPLAY 0.617021 (-6300 1450);
PAINT AQUA (-6300 1450);
DISPLAY INVISIBLE (-6300 1450);
FORCEPROP 1 LAST PATH I95
J 2
(-6300 1500);
DISPLAY 0.978723 (-6300 1500);
PAINT WHITE (-6300 1500);
DISPLAY INVISIBLE (-6300 1500);
FORCEPROP 2 LAST ROOM PCIE_STEERING
J 2
(-6250 1350);
PAINT MONO (-6250 1350);
DISPLAY INVISIBLE (-6250 1350);
FORCEPROP 1 LASTPIN (-6250 1250) $PN 2
J 2
(-6260 1230);
DISPLAY 0.787234 (-6260 1230);
PAINT ORANGE (-6260 1230);
DISPLAY INVISIBLE (-6260 1230);
FORCEPROP 1 LASTPIN (-6250 1450) $PN 1
J 2
(-6260 1430);
DISPLAY 0.787234 (-6260 1430);
PAINT ORANGE (-6260 1430);
DISPLAY INVISIBLE (-6260 1430);
FORCEADD TAP..7
(-6250 1100);
FORCEPROP 3 LASTPIN (-6250 1150) SIG_NAME P3E_OCP_CPU0_PE3_C_TXN<11>
J 0
(-6240 1160);
DISPLAY 0.659574 (-6240 1160);
PAINT MONO (-6240 1160);
DISPLAY INVISIBLE (-6240 1160);
FORCEPROP 1 LASTPIN (-6250 1150) BN 11
R 1
J 0
(-6257 1098);
DISPLAY 0.617021 (-6257 1098);
PAINT GREEN (-6257 1098);
FORCEPROP 2 LAST CDS_LIB mstr_standard
J 0
(-6250 1100);
PAINT ORANGE (-6250 1100);
DISPLAY INVISIBLE (-6250 1100);
FORCEPROP 1 LAST BODY_TYPE PLUMBING
J 0
(-6200 1100);
DISPLAY 2.276596 (-6200 1100);
PAINT GREEN (-6200 1100);
DISPLAY INVISIBLE (-6200 1100);
FORCEPROP 1 LAST HDL_TAP TRUE
J 0
(-5930 970);
DISPLAY 2.276596 (-5930 970);
PAINT GREEN (-5930 970);
DISPLAY INVISIBLE (-5930 970);
FORCEPROP 1 LAST PATH I96
J 0
(-6252 1100);
DISPLAY 0.872340 (-6252 1100);
PAINT GREEN (-6252 1100);
DISPLAY INVISIBLE (-6252 1100);
FORCEADD TAP..3
(-6500 2900);
FORCEPROP 3 LASTPIN (-6500 2850) SIG_NAME P3E_CPU0_PE3_OCP_TXP<12>
J 0
(-6490 2860);
DISPLAY 0.659574 (-6490 2860);
PAINT MONO (-6490 2860);
DISPLAY INVISIBLE (-6490 2860);
FORCEPROP 1 LASTPIN (-6500 2850) BN 12
R 1
J 0
(-6507 2838);
DISPLAY 0.617021 (-6507 2838);
PAINT GREEN (-6507 2838);
FORCEPROP 2 LAST CDS_LIB mstr_standard
J 0
(-6500 2900);
PAINT ORANGE (-6500 2900);
DISPLAY INVISIBLE (-6500 2900);
FORCEPROP 1 LAST BODY_TYPE PLUMBING
J 0
(-6450 2850);
DISPLAY 2.276596 (-6450 2850);
PAINT GREEN (-6450 2850);
DISPLAY INVISIBLE (-6450 2850);
FORCEPROP 1 LAST HDL_TAP TRUE
J 0
(-6180 2770);
DISPLAY 2.276596 (-6180 2770);
PAINT GREEN (-6180 2770);
DISPLAY INVISIBLE (-6180 2770);
FORCEPROP 1 LAST PATH I97
J 0
(-6502 2900);
DISPLAY 0.872340 (-6502 2900);
PAINT GREEN (-6502 2900);
DISPLAY INVISIBLE (-6502 2900);
FORCEADD TAP..3
(-6700 2900);
FORCEPROP 3 LASTPIN (-6700 2850) SIG_NAME P3E_CPU0_PE3_OCP_TXP<13>
J 0
(-6690 2860);
DISPLAY 0.659574 (-6690 2860);
PAINT MONO (-6690 2860);
DISPLAY INVISIBLE (-6690 2860);
FORCEPROP 1 LASTPIN (-6700 2850) BN 13
R 1
J 0
(-6707 2838);
DISPLAY 0.617021 (-6707 2838);
PAINT GREEN (-6707 2838);
FORCEPROP 2 LAST CDS_LIB mstr_standard
J 0
(-6700 2900);
PAINT ORANGE (-6700 2900);
DISPLAY INVISIBLE (-6700 2900);
FORCEPROP 1 LAST BODY_TYPE PLUMBING
J 0
(-6650 2850);
DISPLAY 2.276596 (-6650 2850);
PAINT GREEN (-6650 2850);
DISPLAY INVISIBLE (-6650 2850);
FORCEPROP 1 LAST HDL_TAP TRUE
J 0
(-6380 2770);
DISPLAY 2.276596 (-6380 2770);
PAINT GREEN (-6380 2770);
DISPLAY INVISIBLE (-6380 2770);
FORCEPROP 1 LAST PATH I98
J 0
(-6702 2900);
DISPLAY 0.872340 (-6702 2900);
PAINT GREEN (-6702 2900);
DISPLAY INVISIBLE (-6702 2900);
FORCEADD TAP..3
(-6900 2900);
FORCEPROP 3 LASTPIN (-6900 2850) SIG_NAME P3E_CPU0_PE3_OCP_TXP<14>
J 0
(-6890 2860);
DISPLAY 0.659574 (-6890 2860);
PAINT MONO (-6890 2860);
DISPLAY INVISIBLE (-6890 2860);
FORCEPROP 1 LASTPIN (-6900 2850) BN 14
R 1
J 0
(-6907 2838);
DISPLAY 0.617021 (-6907 2838);
PAINT GREEN (-6907 2838);
FORCEPROP 2 LAST CDS_LIB mstr_standard
J 0
(-6900 2900);
PAINT ORANGE (-6900 2900);
DISPLAY INVISIBLE (-6900 2900);
FORCEPROP 1 LAST BODY_TYPE PLUMBING
J 0
(-6850 2850);
DISPLAY 2.276596 (-6850 2850);
PAINT GREEN (-6850 2850);
DISPLAY INVISIBLE (-6850 2850);
FORCEPROP 1 LAST HDL_TAP TRUE
J 0
(-6580 2770);
DISPLAY 2.276596 (-6580 2770);
PAINT GREEN (-6580 2770);
DISPLAY INVISIBLE (-6580 2770);
FORCEPROP 1 LAST PATH I99
J 0
(-6902 2900);
DISPLAY 0.872340 (-6902 2900);
PAINT GREEN (-6902 2900);
DISPLAY INVISIBLE (-6902 2900);
FORCEADD CAD_NOTE..1
(-7175 600);
FORCEPROP 0 LAST L1 PLACE CLOSE TO CPU
J 0
(-7300 475);
DISPLAY 1.021277 (-7300 475);
PAINT ORANGE (-7300 475);
FORCEPROP 2 LAST CDS_LIB mstr_symbols
J 0
(-7175 600);
PAINT ORANGE (-7175 600);
DISPLAY INVISIBLE (-7175 600);
FORCEPROP 1 LAST COMMENT_BODY TRUE
J 0
(-7150 700);
DISPLAY 0.978723 (-7150 700);
PAINT ORANGE (-7150 700);
DISPLAY INVISIBLE (-7150 700);
FORCEADD INTEL_CORP_BPAGE..1
(-1300 -600);
FORCEPROP 1 LAST CDS_CON_LAST_MODIFIED Fri Jun 16 17:48:42 2017
J 0
(-2725 -275);
DISPLAY 1.361702 (-2725 -275);
PAINT GREEN (-2725 -275);
DISPLAY INVISIBLE (-2725 -275);
FORCEPROP 1 LAST CUSTOM_TXT_CDS <CURRENT_DESIGN_SHEET> OF <TOTAL_DESIGN_SHEETS>
J 0
(-1800 -575);
PAINT ORANGE (-1800 -575);
FORCEPROP 1 LAST CUSTOM_TXT_CDS <CON_LAST_MODIFIED>
J 0
(-5300 -500);
PAINT ORANGE (-5300 -500);
FORCEPROP 2 LAST CUSTOM_TXT_CDS <XR_PAGE_TITLE>
J 0
(-9190 4650);
DISPLAY 0.638298 (-9190 4650);
PAINT PINK (-9190 4650);
DISPLAY INVISIBLE (-9190 4650);
FORCEPROP 1 LAST SCH_TITLE CPU OCP TX CAPS
J 0
(-9250 -550);
DISPLAY 1.212766 (-9250 -550);
PAINT ORANGE (-9250 -550);
FORCEPROP 2 LAST PAGE_BORDER TRUE
J 0
(-9190 4650);
DISPLAY 0.851064 (-9190 4650);
PAINT PINK (-9190 4650);
DISPLAY INVISIBLE (-9190 4650);
FORCEPROP 2 LAST CDS_LIB mstr_symbols
J 0
(-1300 -600);
DISPLAY 1.361702 (-1300 -600);
PAINT ORANGE (-1300 -600);
DISPLAY INVISIBLE (-1300 -600);
FORCEPROP 1 LAST COMMENT_BODY TRUE
J 0
(-1288 -588);
DISPLAY 0.617021 (-1288 -588);
PAINT GREEN (-1288 -588);
DISPLAY INVISIBLE (-1288 -588);
FORCEPROP 2 LAST CDS_XR_PAGE_TITLE CR-106 : @BASEBOARD_FAB2_LIB.BASEBOARD_FAB2(SCH_1):PAGE106
J 0
(-9190 4650);
DISPLAY 0.638298 (-9190 4650);
PAINT PINK (-9190 4650);
DISPLAY INVISIBLE (-9190 4650);
WIRE 17 -1 (-7075 1950)(-7175 1950);
FORCEPROP 0 LAST SIG_NAME P3E_CPU0_PE3_OCP_TXN<15:0>
J 0
(-7135 1960);
DISPLAY 0.617021 (-7135 1960);
PAINT ORANGE (-7135 1960);
WIRE 17 -1 (-6875 1950)(-7075 1950);
WIRE 17 -1 (-6675 1950)(-6875 1950);
WIRE 17 -1 (-6475 1950)(-6675 1950);
WIRE 17 -1 (-6275 1950)(-6475 1950);
WIRE 17 -1 (-6075 1950)(-6275 1950);
WIRE 17 -1 (-5875 1950)(-6075 1950);
WIRE 17 -1 (-5875 1950)(-5675 1950);
WIRE 17 -1 (-5675 1950)(-5500 1950);
WIRE 17 -1 (-5500 1950)(-5300 1950);
WIRE 17 -1 (-5300 1950)(-5100 1950);
WIRE 17 -1 (-5100 1950)(-4900 1950);
WIRE 17 -1 (-4700 1950)(-4900 1950);
WIRE 17 -1 (-4700 1950)(-4500 1950);
WIRE 17 -1 (-4500 1950)(-4300 1950);
WIRE 17 -1 (-4300 1950)(-4100 1950);
WIRE 17 -1 (-7025 1050)(-6825 1050);
WIRE 17 -1 (-6625 1050)(-6825 1050);
WIRE 17 -1 (-6425 1050)(-6625 1050);
WIRE 17 -1 (-6225 1050)(-6425 1050);
WIRE 17 -1 (-6025 1050)(-6225 1050);
WIRE 17 -1 (-5825 1050)(-6025 1050);
WIRE 17 -1 (-5625 1050)(-5825 1050);
WIRE 17 -1 (-5450 1050)(-5625 1050);
WIRE 17 -1 (-5450 1050)(-5250 1050);
FORCEPROP 2 LAST SIG_NAME P3E_OCP_CPU0_PE3_C_TXN<15:0>
J 0
(-4460 1010);
DISPLAY 0.617021 (-4460 1010);
PAINT ORANGE (-4460 1010);
WIRE 17 -1 (-5250 1050)(-5050 1050);
WIRE 17 -1 (-5050 1050)(-4850 1050);
WIRE 17 -1 (-4850 1050)(-4650 1050);
WIRE 17 -1 (-4450 1050)(-4650 1050);
WIRE 17 -1 (-4450 1050)(-4250 1050);
WIRE 17 -1 (-4250 1050)(-4050 1050);
WIRE 17 -1 (-4050 1050)(-3800 1050);
WIRE 17 -1 (-7125 2950)(-7225 2950);
FORCEPROP 0 LAST SIG_NAME P3E_CPU0_PE3_OCP_TXP<15:0>
J 0
(-7185 2960);
DISPLAY 0.617021 (-7185 2960);
PAINT ORANGE (-7185 2960);
WIRE 17 -1 (-6925 2950)(-7125 2950);
WIRE 17 -1 (-6725 2950)(-6925 2950);
WIRE 17 -1 (-6525 2950)(-6725 2950);
WIRE 17 -1 (-6325 2950)(-6525 2950);
WIRE 17 -1 (-6125 2950)(-6325 2950);
WIRE 17 -1 (-5925 2950)(-6125 2950);
WIRE 17 -1 (-5725 2950)(-5925 2950);
WIRE 17 -1 (-5725 2950)(-5525 2950);
WIRE 17 -1 (-5525 2950)(-5325 2950);
WIRE 17 -1 (-5325 2950)(-5125 2950);
WIRE 17 -1 (-5125 2950)(-4925 2950);
WIRE 17 -1 (-4725 2950)(-4925 2950);
WIRE 17 -1 (-4525 2950)(-4725 2950);
WIRE 17 -1 (-4525 2950)(-4325 2950);
WIRE 17 -1 (-4325 2950)(-4125 2950);
WIRE 17 -1 (-6875 2050)(-7075 2050);
WIRE 17 -1 (-6675 2050)(-6875 2050);
WIRE 17 -1 (-6475 2050)(-6675 2050);
WIRE 17 -1 (-6275 2050)(-6475 2050);
WIRE 17 -1 (-6075 2050)(-6275 2050);
WIRE 17 -1 (-5875 2050)(-6075 2050);
WIRE 17 -1 (-5675 2050)(-5875 2050);
WIRE 17 -1 (-5475 2050)(-5675 2050);
WIRE 17 -1 (-5475 2050)(-5275 2050);
FORCEPROP 2 LAST SIG_NAME P3E_OCP_CPU0_PE3_C_TXP<15:0>
J 0
(-4510 2010);
DISPLAY 0.617021 (-4510 2010);
PAINT ORANGE (-4510 2010);
WIRE 17 -1 (-5275 2050)(-5075 2050);
WIRE 17 -1 (-5075 2050)(-4875 2050);
WIRE 17 -1 (-4875 2050)(-4675 2050);
WIRE 17 -1 (-4475 2050)(-4675 2050);
WIRE 17 -1 (-4475 2050)(-4275 2050);
WIRE 17 -1 (-4275 2050)(-4075 2050);
WIRE 17 -1 (-4075 2050)(-3800 2050);
WIRE 16 -1 (-7050 1150)(-7050 1250);
WIRE 16 -1 (-7050 1850)(-7050 1450);
WIRE 16 -1 (-6850 1550)(-6850 1150);
WIRE 16 -1 (-6850 1850)(-6850 1750);
WIRE 16 -1 (-6650 1150)(-6650 1250);
WIRE 16 -1 (-6250 1150)(-6250 1250);
WIRE 16 -1 (-6650 1850)(-6650 1450);
WIRE 16 -1 (-6250 1850)(-6250 1450);
WIRE 16 -1 (-6450 1150)(-6450 1550);
WIRE 16 -1 (-6450 1850)(-6450 1750);
WIRE 16 -1 (-7100 2150)(-7100 2250);
WIRE 16 -1 (-6700 2150)(-6700 2250);
WIRE 16 -1 (-6900 2550)(-6900 2150);
WIRE 16 -1 (-6700 2850)(-6700 2450);
WIRE 16 -1 (-7100 2850)(-7100 2450);
WIRE 16 -1 (-6900 2850)(-6900 2750);
WIRE 16 -1 (-6500 2150)(-6500 2550);
WIRE 16 -1 (-6300 2150)(-6300 2250);
WIRE 16 -1 (-6300 2850)(-6300 2450);
WIRE 16 -1 (-6500 2850)(-6500 2750);
WIRE 16 -1 (-5850 1150)(-5850 1250);
WIRE 16 -1 (-5650 1150)(-5650 1550);
WIRE 16 -1 (-6050 1150)(-6050 1550);
WIRE 16 -1 (-5850 1450)(-5850 1850);
WIRE 16 -1 (-6050 1750)(-6050 1850);
WIRE 16 -1 (-5650 1750)(-5650 1850);
WIRE 16 -1 (-5475 1150)(-5475 1250);
WIRE 16 -1 (-5475 1850)(-5475 1450);
WIRE 16 -1 (-5275 1150)(-5275 1550);
WIRE 16 -1 (-5275 1750)(-5275 1850);
WIRE 16 -1 (-5075 1150)(-5075 1250);
WIRE 16 -1 (-4675 1150)(-4675 1250);
WIRE 16 -1 (-4875 1150)(-4875 1550);
WIRE 16 -1 (-5075 1450)(-5075 1850);
WIRE 16 -1 (-4675 1850)(-4675 1450);
WIRE 16 -1 (-4875 1750)(-4875 1850);
WIRE 16 -1 (-4275 1150)(-4275 1250);
WIRE 16 -1 (-4275 1850)(-4275 1450);
WIRE 16 -1 (-4475 1550)(-4475 1150);
WIRE 16 -1 (-4475 1850)(-4475 1750);
WIRE 16 -1 (-5900 2150)(-5900 2250);
WIRE 16 -1 (-6100 2150)(-6100 2550);
WIRE 16 -1 (-5700 2150)(-5700 2550);
WIRE 16 -1 (-5900 2450)(-5900 2850);
WIRE 16 -1 (-6100 2750)(-6100 2850);
WIRE 16 -1 (-5700 2750)(-5700 2850);
WIRE 16 -1 (-5500 2150)(-5500 2250);
WIRE 16 -1 (-5300 2150)(-5300 2550);
WIRE 16 -1 (-5500 2850)(-5500 2450);
WIRE 16 -1 (-5300 2750)(-5300 2850);
WIRE 16 -1 (-5100 2150)(-5100 2250);
WIRE 16 -1 (-4900 2150)(-4900 2550);
WIRE 16 -1 (-4700 2150)(-4700 2250);
WIRE 16 -1 (-5100 2450)(-5100 2850);
WIRE 16 -1 (-4700 2850)(-4700 2450);
WIRE 16 -1 (-4900 2750)(-4900 2850);
WIRE 16 -1 (-4500 2550)(-4500 2150);
WIRE 16 -1 (-4300 2150)(-4300 2250);
WIRE 16 -1 (-4100 2150)(-4100 2550);
WIRE 16 -1 (-4300 2850)(-4300 2450);
WIRE 16 -1 (-4500 2850)(-4500 2750);
WIRE 16 -1 (-4100 2850)(-4100 2750);
WIRE 16 -1 (-4075 1150)(-4075 1550);
WIRE 16 -1 (-4075 1850)(-4075 1750);
FORCENOTE
CPU0 TO OCP MEZZ TX CAPS
(-6075 3050) 0;
DISPLAY LEFT (-6075 3050);
DISPLAY 1.021277 (-6075 3050);
PAINT PURPLE (-6075 3050);
FORCENOTE
FROM CPU0
(-7850 2200) 0;
DISPLAY LEFT (-7850 2200);
DISPLAY 1.021277 (-7850 2200);
PAINT PURPLE (-7850 2200);
FORCENOTE
DE NOTE:
(-6075 3125) 0;
DISPLAY LEFT (-6075 3125);
DISPLAY 1.021277 (-6075 3125);
PAINT PURPLE (-6075 3125);
FORCENOTE
TO OCP 
(-3475 1725) 0;
DISPLAY LEFT (-3475 1725);
DISPLAY 1.021277 (-3475 1725);
PAINT PURPLE (-3475 1725);
QUIT
